FILE_TYPE = MACRO_DRAWING;
SET COLOR_WIRE YELLOW;
SET COLOR_PROP MONO;
SET COLOR_DOT WHITE;
SET COLOR_ARC YELLOW;
SET COLOR_BODY GREEN;
SET COLOR_NOTE MONO;
SET PROP_DISPLAY VALUE;
SET PAGE_NUMBER P191;
FORCEADD OFFPAGE..4
(-2450 4225);
FORCEPROP 2 LAST $XR0 181 
J 0
(-2264 4225);
DISPLAY 0.638298 (-2264 4225);
PAINT MONO (-2264 4225);
FORCEPROP 2 LAST $XR1 161 
J 0
(-2144 4225);
DISPLAY 0.638298 (-2144 4225);
PAINT MONO (-2144 4225);
FORCEPROP 2 LAST $XR2 198 
J 0
(-2024 4225);
DISPLAY 0.638298 (-2024 4225);
PAINT MONO (-2024 4225);
FORCEPROP 2 LAST CDS_LIB mstr_standard
J 0
(-2450 4225);
PAINT ORANGE (-2450 4225);
DISPLAY INVISIBLE (-2450 4225);
FORCEPROP 1 LAST OFFPAGE TRUE
J 0
(-2125 4100);
DISPLAY 1.170213 (-2125 4100);
PAINT GREEN (-2125 4100);
DISPLAY INVISIBLE (-2125 4100);
FORCEPROP 1 LAST COMMENT_BODY TRUE
J 0
(-2475 4125);
DISPLAY 1.170213 (-2475 4125);
PAINT GREEN (-2475 4125);
DISPLAY INVISIBLE (-2475 4125);
FORCEPROP 2 LAST PATH I1
J 0
(-1800 4275);
DISPLAY 1.021277 (-1800 4275);
PAINT ORANGE (-1800 4275);
DISPLAY INVISIBLE (-1800 4275);
FORCEADD OFFPAGE..4
R 2
(-6425 2125);
FORCEPROP 2 LAST $XR0 240 
J 0
(-6677 2125);
DISPLAY 0.638298 (-6677 2125);
PAINT MONO (-6677 2125);
FORCEPROP 2 LAST $XR1 101 
J 0
(-6797 2125);
DISPLAY 0.638298 (-6797 2125);
PAINT MONO (-6797 2125);
FORCEPROP 2 LAST $XR2 189 
J 0
(-6917 2125);
DISPLAY 0.638298 (-6917 2125);
PAINT MONO (-6917 2125);
FORCEPROP 2 LAST $XR3 196 
J 0
(-7037 2125);
DISPLAY 0.638298 (-7037 2125);
PAINT MONO (-7037 2125);
FORCEPROP 2 LAST $XR4 237 
J 0
(-7157 2125);
DISPLAY 0.638298 (-7157 2125);
PAINT MONO (-7157 2125);
FORCEPROP 2 LAST $XR5 239 
J 0
(-7277 2125);
DISPLAY 0.638298 (-7277 2125);
PAINT MONO (-7277 2125);
FORCEPROP 2 LAST CDS_LIB mstr_standard
J 0
(-6425 2125);
PAINT ORANGE (-6425 2125);
DISPLAY INVISIBLE (-6425 2125);
FORCEPROP 1 LAST OFFPAGE TRUE
J 2
(-6750 2000);
DISPLAY 1.170213 (-6750 2000);
PAINT GREEN (-6750 2000);
DISPLAY INVISIBLE (-6750 2000);
FORCEPROP 1 LAST COMMENT_BODY TRUE
J 2
(-6400 2025);
DISPLAY 1.170213 (-6400 2025);
PAINT GREEN (-6400 2025);
DISPLAY INVISIBLE (-6400 2025);
FORCEPROP 2 LAST PATH I102
J 0
(-6375 2200);
DISPLAY 1.021277 (-6375 2200);
PAINT ORANGE (-6375 2200);
DISPLAY INVISIBLE (-6375 2200);
FORCEADD OFFPAGE..4
R 2
(-6425 3225);
FORCEPROP 2 LAST $XR0 92 
J 0
(-6646 3225);
DISPLAY 0.638298 (-6646 3225);
PAINT MONO (-6646 3225);
FORCEPROP 2 LAST CDS_LIB mstr_standard
J 0
(-6425 3225);
PAINT ORANGE (-6425 3225);
DISPLAY INVISIBLE (-6425 3225);
FORCEPROP 1 LAST OFFPAGE TRUE
J 2
(-6750 3100);
DISPLAY 1.170213 (-6750 3100);
PAINT GREEN (-6750 3100);
DISPLAY INVISIBLE (-6750 3100);
FORCEPROP 1 LAST COMMENT_BODY TRUE
J 2
(-6400 3125);
DISPLAY 1.170213 (-6400 3125);
PAINT GREEN (-6400 3125);
DISPLAY INVISIBLE (-6400 3125);
FORCEPROP 2 LAST PATH I115
J 0
(-6375 3300);
DISPLAY 1.021277 (-6375 3300);
PAINT ORANGE (-6375 3300);
DISPLAY INVISIBLE (-6375 3300);
FORCEADD OFFPAGE..2
R 2
(-6425 4025);
FORCEPROP 2 LAST $XR0 120 
J 0
(-6680 4025);
DISPLAY 0.638298 (-6680 4025);
PAINT MONO (-6680 4025);
FORCEPROP 2 LAST CDS_LIB mstr_standard
J 0
(-6425 4025);
PAINT ORANGE (-6425 4025);
DISPLAY INVISIBLE (-6425 4025);
FORCEPROP 1 LAST OFFPAGE TRUE
J 2
(-6750 3900);
DISPLAY 1.170213 (-6750 3900);
PAINT GREEN (-6750 3900);
DISPLAY INVISIBLE (-6750 3900);
FORCEPROP 1 LAST COMMENT_BODY TRUE
J 2
(-6380 3930);
DISPLAY 1.170213 (-6380 3930);
PAINT GREEN (-6380 3930);
DISPLAY INVISIBLE (-6380 3930);
FORCEPROP 2 LAST PATH I118
J 0
(-6375 4100);
DISPLAY 1.021277 (-6375 4100);
PAINT ORANGE (-6375 4100);
DISPLAY INVISIBLE (-6375 4100);
FORCEADD OFFPAGE..2
R 2
(-6425 3975);
FORCEPROP 2 LAST $XR0 133 
J 0
(-6680 3975);
DISPLAY 0.638298 (-6680 3975);
PAINT MONO (-6680 3975);
FORCEPROP 2 LAST $XR1 118 
J 0
(-6800 3975);
DISPLAY 0.638298 (-6800 3975);
PAINT MONO (-6800 3975);
FORCEPROP 2 LAST $XR2 144 
J 0
(-6920 3975);
DISPLAY 0.638298 (-6920 3975);
PAINT MONO (-6920 3975);
FORCEPROP 2 LAST CDS_LIB mstr_standard
J 0
(-6425 3975);
PAINT ORANGE (-6425 3975);
DISPLAY INVISIBLE (-6425 3975);
FORCEPROP 1 LAST OFFPAGE TRUE
J 2
(-6750 3850);
DISPLAY 1.170213 (-6750 3850);
PAINT GREEN (-6750 3850);
DISPLAY INVISIBLE (-6750 3850);
FORCEPROP 1 LAST COMMENT_BODY TRUE
J 2
(-6380 3880);
DISPLAY 1.170213 (-6380 3880);
PAINT GREEN (-6380 3880);
DISPLAY INVISIBLE (-6380 3880);
FORCEPROP 2 LAST PATH I120
J 0
(-6375 4050);
DISPLAY 1.021277 (-6375 4050);
PAINT ORANGE (-6375 4050);
DISPLAY INVISIBLE (-6375 4050);
FORCEADD OFFPAGE..2
R 2
(-6425 3525);
FORCEPROP 2 LAST $XR0 156 
J 0
(-6680 3525);
DISPLAY 0.638298 (-6680 3525);
PAINT MONO (-6680 3525);
FORCEPROP 2 LAST $XR1 118 
J 0
(-6800 3525);
DISPLAY 0.638298 (-6800 3525);
PAINT MONO (-6800 3525);
FORCEPROP 2 LAST CDS_LIB mstr_standard
J 0
(-6425 3525);
PAINT ORANGE (-6425 3525);
DISPLAY INVISIBLE (-6425 3525);
FORCEPROP 1 LAST OFFPAGE TRUE
J 2
(-6750 3400);
DISPLAY 1.170213 (-6750 3400);
PAINT GREEN (-6750 3400);
DISPLAY INVISIBLE (-6750 3400);
FORCEPROP 1 LAST COMMENT_BODY TRUE
J 2
(-6380 3430);
DISPLAY 1.170213 (-6380 3430);
PAINT GREEN (-6380 3430);
DISPLAY INVISIBLE (-6380 3430);
FORCEPROP 2 LAST PATH I123
J 0
(-6375 3600);
DISPLAY 1.021277 (-6375 3600);
PAINT ORANGE (-6375 3600);
DISPLAY INVISIBLE (-6375 3600);
FORCEADD OFFPAGE..4
R 2
(-6425 3675);
FORCEPROP 2 LAST $XR0 92 
J 0
(-6676 3675);
DISPLAY 0.638298 (-6676 3675);
PAINT MONO (-6676 3675);
FORCEPROP 2 LAST CDS_LIB mstr_standard
J 0
(-6425 3675);
PAINT ORANGE (-6425 3675);
DISPLAY INVISIBLE (-6425 3675);
FORCEPROP 1 LAST OFFPAGE TRUE
J 2
(-6750 3550);
DISPLAY 0.872340 (-6750 3550);
PAINT GREEN (-6750 3550);
DISPLAY INVISIBLE (-6750 3550);
FORCEPROP 1 LAST COMMENT_BODY TRUE
J 2
(-6400 3575);
DISPLAY 0.872340 (-6400 3575);
PAINT GREEN (-6400 3575);
DISPLAY INVISIBLE (-6400 3575);
FORCEPROP 2 LAST PATH I125
J 0
(-6375 3750);
DISPLAY 1.021277 (-6375 3750);
PAINT ORANGE (-6375 3750);
DISPLAY INVISIBLE (-6375 3750);
FORCEADD OFFPAGE..4
R 2
(-6425 4275);
FORCEPROP 2 LAST $XR0 119 
J 0
(-6707 4275);
DISPLAY 0.638298 (-6707 4275);
PAINT MONO (-6707 4275);
FORCEPROP 2 LAST $XR1 136 
J 0
(-6827 4275);
DISPLAY 0.638298 (-6827 4275);
PAINT MONO (-6827 4275);
FORCEPROP 2 LAST $XR2 139 
J 0
(-6947 4275);
DISPLAY 0.638298 (-6947 4275);
PAINT MONO (-6947 4275);
FORCEPROP 2 LAST CDS_LIB mstr_standard
J 0
(-6425 4275);
PAINT ORANGE (-6425 4275);
DISPLAY INVISIBLE (-6425 4275);
FORCEPROP 1 LAST OFFPAGE TRUE
J 2
(-6750 4150);
DISPLAY 1.170213 (-6750 4150);
PAINT GREEN (-6750 4150);
DISPLAY INVISIBLE (-6750 4150);
FORCEPROP 1 LAST COMMENT_BODY TRUE
J 2
(-6400 4175);
DISPLAY 1.170213 (-6400 4175);
PAINT GREEN (-6400 4175);
DISPLAY INVISIBLE (-6400 4175);
FORCEPROP 2 LAST PATH I127
J 0
(-6375 4350);
DISPLAY 1.021277 (-6375 4350);
PAINT ORANGE (-6375 4350);
DISPLAY INVISIBLE (-6375 4350);
FORCEADD OFFPAGE..2
R 2
(-6425 4325);
FORCEPROP 2 LAST $XR0 133 
J 0
(-6680 4325);
DISPLAY 0.638298 (-6680 4325);
PAINT MONO (-6680 4325);
FORCEPROP 2 LAST $XR1 118 
J 0
(-6800 4325);
DISPLAY 0.638298 (-6800 4325);
PAINT MONO (-6800 4325);
FORCEPROP 2 LAST $XR2 144 
J 0
(-6920 4325);
DISPLAY 0.638298 (-6920 4325);
PAINT MONO (-6920 4325);
FORCEPROP 2 LAST CDS_LIB mstr_standard
J 0
(-6425 4325);
PAINT ORANGE (-6425 4325);
DISPLAY INVISIBLE (-6425 4325);
FORCEPROP 1 LAST OFFPAGE TRUE
J 2
(-6750 4200);
DISPLAY 1.170213 (-6750 4200);
PAINT GREEN (-6750 4200);
DISPLAY INVISIBLE (-6750 4200);
FORCEPROP 1 LAST COMMENT_BODY TRUE
J 2
(-6380 4230);
DISPLAY 1.170213 (-6380 4230);
PAINT GREEN (-6380 4230);
DISPLAY INVISIBLE (-6380 4230);
FORCEPROP 2 LAST PATH I128
J 0
(-6375 4400);
DISPLAY 1.021277 (-6375 4400);
PAINT ORANGE (-6375 4400);
DISPLAY INVISIBLE (-6375 4400);
FORCEADD OFFPAGE..2
R 2
(-6425 4175);
FORCEPROP 2 LAST $XR0 89 
J 0
(-6679 4175);
DISPLAY 0.638298 (-6679 4175);
PAINT MONO (-6679 4175);
FORCEPROP 2 LAST CDS_LIB mstr_standard
J 0
(-6425 4175);
PAINT ORANGE (-6425 4175);
DISPLAY INVISIBLE (-6425 4175);
FORCEPROP 1 LAST OFFPAGE TRUE
J 2
(-6750 4050);
DISPLAY 1.170213 (-6750 4050);
PAINT GREEN (-6750 4050);
DISPLAY INVISIBLE (-6750 4050);
FORCEPROP 1 LAST COMMENT_BODY TRUE
J 2
(-6380 4080);
DISPLAY 1.170213 (-6380 4080);
PAINT GREEN (-6380 4080);
DISPLAY INVISIBLE (-6380 4080);
FORCEPROP 2 LAST PATH I129
J 0
(-6375 4250);
DISPLAY 1.021277 (-6375 4250);
PAINT ORANGE (-6375 4250);
DISPLAY INVISIBLE (-6375 4250);
FORCEADD OFFPAGE..2
R 2
(-6425 1375);
FORCEPROP 2 LAST $XR0 233 
J 0
(-6680 1375);
DISPLAY 0.638298 (-6680 1375);
PAINT MONO (-6680 1375);
FORCEPROP 2 LAST $XR1 234 
J 0
(-6800 1375);
DISPLAY 0.638298 (-6800 1375);
PAINT MONO (-6800 1375);
FORCEPROP 2 LAST CDS_LIB mstr_standard
J 0
(-6425 1375);
PAINT ORANGE (-6425 1375);
DISPLAY INVISIBLE (-6425 1375);
FORCEPROP 1 LAST OFFPAGE TRUE
J 2
(-6750 1250);
DISPLAY 1.170213 (-6750 1250);
PAINT GREEN (-6750 1250);
DISPLAY INVISIBLE (-6750 1250);
FORCEPROP 1 LAST COMMENT_BODY TRUE
J 2
(-6380 1280);
DISPLAY 1.170213 (-6380 1280);
PAINT GREEN (-6380 1280);
DISPLAY INVISIBLE (-6380 1280);
FORCEPROP 2 LAST PATH I132
J 0
(-6375 1450);
DISPLAY 1.021277 (-6375 1450);
PAINT ORANGE (-6375 1450);
DISPLAY INVISIBLE (-6375 1450);
FORCEADD OFFPAGE..4
R 2
(-6425 1425);
FORCEPROP 2 LAST $XR0 92 
J 0
(-6646 1425);
DISPLAY 0.638298 (-6646 1425);
PAINT MONO (-6646 1425);
FORCEPROP 2 LAST CDS_LIB mstr_standard
J 0
(-6425 1425);
PAINT ORANGE (-6425 1425);
DISPLAY INVISIBLE (-6425 1425);
FORCEPROP 1 LAST OFFPAGE TRUE
J 2
(-6750 1300);
DISPLAY 1.170213 (-6750 1300);
PAINT GREEN (-6750 1300);
DISPLAY INVISIBLE (-6750 1300);
FORCEPROP 1 LAST COMMENT_BODY TRUE
J 2
(-6400 1325);
DISPLAY 1.170213 (-6400 1325);
PAINT GREEN (-6400 1325);
DISPLAY INVISIBLE (-6400 1325);
FORCEPROP 2 LAST PATH I133
J 0
(-6375 1500);
DISPLAY 1.021277 (-6375 1500);
PAINT ORANGE (-6375 1500);
DISPLAY INVISIBLE (-6375 1500);
FORCEADD OFFPAGE..4
R 2
(-6425 1475);
FORCEPROP 2 LAST $XR0 55 
J 0
(-6646 1475);
DISPLAY 0.638298 (-6646 1475);
PAINT MONO (-6646 1475);
FORCEPROP 2 LAST $XR2 146 
J 0
(-6646 1475);
DISPLAY 0.638298 (-6646 1475);
PAINT MONO (-6646 1475);
FORCEPROP 2 LAST $XR1 151 
J 0
(-6646 1475);
DISPLAY 0.638298 (-6646 1475);
PAINT MONO (-6646 1475);
FORCEPROP 2 LAST CDS_LIB mstr_standard
J 0
(-6425 1475);
PAINT ORANGE (-6425 1475);
DISPLAY INVISIBLE (-6425 1475);
FORCEPROP 1 LAST OFFPAGE TRUE
J 2
(-6750 1350);
DISPLAY 1.170213 (-6750 1350);
PAINT GREEN (-6750 1350);
DISPLAY INVISIBLE (-6750 1350);
FORCEPROP 1 LAST COMMENT_BODY TRUE
J 2
(-6400 1375);
DISPLAY 1.170213 (-6400 1375);
PAINT GREEN (-6400 1375);
DISPLAY INVISIBLE (-6400 1375);
FORCEPROP 2 LAST PATH I134
J 0
(-6375 1550);
DISPLAY 1.021277 (-6375 1550);
PAINT ORANGE (-6375 1550);
DISPLAY INVISIBLE (-6375 1550);
FORCEADD OFFPAGE..4
(-2450 1275);
FORCEPROP 2 LAST $XR0 121 
J 0
(-2264 1275);
DISPLAY 0.638298 (-2264 1275);
PAINT MONO (-2264 1275);
FORCEPROP 2 LAST $XR1 133 
J 0
(-2144 1275);
DISPLAY 0.638298 (-2144 1275);
PAINT MONO (-2144 1275);
FORCEPROP 2 LAST CDS_LIB mstr_standard
J 0
(-2450 1275);
PAINT ORANGE (-2450 1275);
DISPLAY INVISIBLE (-2450 1275);
FORCEPROP 1 LAST OFFPAGE TRUE
J 0
(-2125 1150);
DISPLAY 1.170213 (-2125 1150);
PAINT GREEN (-2125 1150);
DISPLAY INVISIBLE (-2125 1150);
FORCEPROP 1 LAST COMMENT_BODY TRUE
J 0
(-2475 1175);
DISPLAY 1.170213 (-2475 1175);
PAINT GREEN (-2475 1175);
DISPLAY INVISIBLE (-2475 1175);
FORCEPROP 2 LAST PATH I135
J 0
(-2275 1350);
DISPLAY 1.021277 (-2275 1350);
PAINT ORANGE (-2275 1350);
DISPLAY INVISIBLE (-2275 1350);
FORCEADD OFFPAGE..2
(-2450 1375);
FORCEPROP 2 LAST $XR0 156 
J 0
(-2261 1375);
DISPLAY 0.638298 (-2261 1375);
PAINT MONO (-2261 1375);
FORCEPROP 2 LAST $XR1 118 
J 0
(-2141 1375);
DISPLAY 0.638298 (-2141 1375);
PAINT MONO (-2141 1375);
FORCEPROP 2 LAST CDS_LIB mstr_standard
J 2
(-2450 1375);
PAINT ORANGE (-2450 1375);
DISPLAY INVISIBLE (-2450 1375);
FORCEPROP 1 LAST OFFPAGE TRUE
J 0
(-2125 1250);
DISPLAY 1.170213 (-2125 1250);
PAINT GREEN (-2125 1250);
DISPLAY INVISIBLE (-2125 1250);
FORCEPROP 1 LAST COMMENT_BODY TRUE
J 0
(-2495 1280);
DISPLAY 1.170213 (-2495 1280);
PAINT GREEN (-2495 1280);
DISPLAY INVISIBLE (-2495 1280);
FORCEPROP 2 LAST PATH I136
J 0
(-2275 1450);
DISPLAY 1.021277 (-2275 1450);
PAINT ORANGE (-2275 1450);
DISPLAY INVISIBLE (-2275 1450);
FORCEADD OFFPAGE..4
(-2450 1425);
FORCEPROP 2 LAST $XR0 118 
J 0
(-2264 1425);
DISPLAY 0.638298 (-2264 1425);
PAINT MONO (-2264 1425);
FORCEPROP 2 LAST $XR1 148 
J 0
(-2144 1425);
DISPLAY 0.638298 (-2144 1425);
PAINT MONO (-2144 1425);
FORCEPROP 2 LAST CDS_LIB mstr_standard
J 0
(-2450 1425);
PAINT ORANGE (-2450 1425);
DISPLAY INVISIBLE (-2450 1425);
FORCEPROP 1 LAST OFFPAGE TRUE
J 0
(-2125 1300);
DISPLAY 1.170213 (-2125 1300);
PAINT GREEN (-2125 1300);
DISPLAY INVISIBLE (-2125 1300);
FORCEPROP 1 LAST COMMENT_BODY TRUE
J 0
(-2475 1325);
DISPLAY 1.170213 (-2475 1325);
PAINT GREEN (-2475 1325);
DISPLAY INVISIBLE (-2475 1325);
FORCEPROP 2 LAST PATH I137
J 0
(-2275 1500);
DISPLAY 1.021277 (-2275 1500);
PAINT ORANGE (-2275 1500);
DISPLAY INVISIBLE (-2275 1500);
FORCEADD OFFPAGE..4
(-2450 2075);
FORCEPROP 2 LAST $XR0 189 
J 0
(-2264 2075);
DISPLAY 0.638298 (-2264 2075);
PAINT MONO (-2264 2075);
FORCEPROP 2 LAST CDS_LIB mstr_standard
J 0
(-2450 2075);
PAINT ORANGE (-2450 2075);
DISPLAY INVISIBLE (-2450 2075);
FORCEPROP 1 LAST OFFPAGE TRUE
J 0
(-2125 1950);
DISPLAY 1.170213 (-2125 1950);
PAINT GREEN (-2125 1950);
DISPLAY INVISIBLE (-2125 1950);
FORCEPROP 1 LAST COMMENT_BODY TRUE
J 0
(-2475 1975);
DISPLAY 1.170213 (-2475 1975);
PAINT GREEN (-2475 1975);
DISPLAY INVISIBLE (-2475 1975);
FORCEPROP 2 LAST PATH I139
J 0
(-2275 2150);
DISPLAY 1.021277 (-2275 2150);
PAINT ORANGE (-2275 2150);
DISPLAY INVISIBLE (-2275 2150);
FORCEADD OFFPAGE..3
(-2450 2525);
FORCEPROP 2 LAST $XR0 167 
J 0
(-2236 2525);
DISPLAY 0.638298 (-2236 2525);
PAINT MONO (-2236 2525);
FORCEPROP 2 LAST $XR1 184 
J 0
(-2116 2525);
DISPLAY 0.638298 (-2116 2525);
PAINT MONO (-2116 2525);
FORCEPROP 2 LAST CDS_LIB mstr_standard
J 0
(-2450 2525);
PAINT ORANGE (-2450 2525);
DISPLAY INVISIBLE (-2450 2525);
FORCEPROP 1 LAST OFFPAGE TRUE
J 0
(-2125 2400);
DISPLAY 1.170213 (-2125 2400);
PAINT GREEN (-2125 2400);
DISPLAY INVISIBLE (-2125 2400);
FORCEPROP 1 LAST COMMENT_BODY TRUE
J 0
(-2500 2425);
DISPLAY 1.170213 (-2500 2425);
PAINT GREEN (-2500 2425);
DISPLAY INVISIBLE (-2500 2425);
FORCEPROP 2 LAST PATH I141
J 0
(-2250 2600);
DISPLAY 1.021277 (-2250 2600);
PAINT ORANGE (-2250 2600);
DISPLAY INVISIBLE (-2250 2600);
FORCEADD OFFPAGE..4
(-2450 2825);
FORCEPROP 2 LAST $XR0 118 
J 0
(-2264 2825);
DISPLAY 0.638298 (-2264 2825);
PAINT MONO (-2264 2825);
FORCEPROP 2 LAST CDS_LIB mstr_standard
J 0
(-2450 2825);
PAINT ORANGE (-2450 2825);
DISPLAY INVISIBLE (-2450 2825);
FORCEPROP 1 LAST OFFPAGE TRUE
J 0
(-2125 2700);
DISPLAY 1.170213 (-2125 2700);
PAINT GREEN (-2125 2700);
DISPLAY INVISIBLE (-2125 2700);
FORCEPROP 1 LAST COMMENT_BODY TRUE
J 0
(-2475 2725);
DISPLAY 1.170213 (-2475 2725);
PAINT GREEN (-2475 2725);
DISPLAY INVISIBLE (-2475 2725);
FORCEPROP 2 LAST PATH I142
J 0
(-2275 2900);
DISPLAY 1.021277 (-2275 2900);
PAINT ORANGE (-2275 2900);
DISPLAY INVISIBLE (-2275 2900);
FORCEADD OFFPAGE..4
(-2450 2975);
FORCEPROP 2 LAST $XR0 120 
J 0
(-2264 2975);
DISPLAY 0.638298 (-2264 2975);
PAINT MONO (-2264 2975);
FORCEPROP 2 LAST $XR1 89 
J 0
(-2144 2975);
DISPLAY 0.638298 (-2144 2975);
PAINT MONO (-2144 2975);
FORCEPROP 2 LAST CDS_LIB mstr_standard
J 0
(-2450 2975);
PAINT ORANGE (-2450 2975);
DISPLAY INVISIBLE (-2450 2975);
FORCEPROP 1 LAST OFFPAGE TRUE
J 0
(-2125 2850);
DISPLAY 1.170213 (-2125 2850);
PAINT GREEN (-2125 2850);
DISPLAY INVISIBLE (-2125 2850);
FORCEPROP 1 LAST COMMENT_BODY TRUE
J 0
(-2475 2875);
DISPLAY 1.170213 (-2475 2875);
PAINT GREEN (-2475 2875);
DISPLAY INVISIBLE (-2475 2875);
FORCEPROP 2 LAST PATH I143
J 0
(-2275 3050);
DISPLAY 1.021277 (-2275 3050);
PAINT ORANGE (-2275 3050);
DISPLAY INVISIBLE (-2275 3050);
FORCEADD OFFPAGE..4
(-2450 3425);
FORCEPROP 2 LAST $XR0 145 
J 0
(-2264 3425);
DISPLAY 0.638298 (-2264 3425);
PAINT MONO (-2264 3425);
FORCEPROP 2 LAST $XRERR ?
J 0
(-2264 3425);
DISPLAY 0.638298 (-2264 3425);
PAINT MONO (-2264 3425);
DISPLAY INVISIBLE (-2264 3425);
FORCEPROP 2 LAST $XRERR ?
J 0
(-2264 3425);
DISPLAY 0.638298 (-2264 3425);
PAINT MONO (-2264 3425);
DISPLAY INVISIBLE (-2264 3425);
FORCEPROP 2 LAST $XRERR ?
J 0
(-2264 3425);
DISPLAY 0.638298 (-2264 3425);
PAINT MONO (-2264 3425);
DISPLAY INVISIBLE (-2264 3425);
FORCEPROP 2 LAST $XRERR ?
J 0
(-2264 3425);
DISPLAY 0.638298 (-2264 3425);
PAINT MONO (-2264 3425);
DISPLAY INVISIBLE (-2264 3425);
FORCEPROP 2 LAST $XRERR ?
J 0
(-2264 3425);
DISPLAY 0.638298 (-2264 3425);
PAINT MONO (-2264 3425);
DISPLAY INVISIBLE (-2264 3425);
FORCEPROP 2 LAST $XRERR ?
J 0
(-2264 3425);
DISPLAY 0.638298 (-2264 3425);
PAINT MONO (-2264 3425);
DISPLAY INVISIBLE (-2264 3425);
FORCEPROP 2 LAST CDS_LIB mstr_standard
J 0
(-2450 3425);
PAINT ORANGE (-2450 3425);
DISPLAY INVISIBLE (-2450 3425);
FORCEPROP 1 LAST OFFPAGE TRUE
J 0
(-2125 3300);
DISPLAY 1.170213 (-2125 3300);
PAINT GREEN (-2125 3300);
DISPLAY INVISIBLE (-2125 3300);
FORCEPROP 1 LAST COMMENT_BODY TRUE
J 0
(-2475 3325);
DISPLAY 1.170213 (-2475 3325);
PAINT GREEN (-2475 3325);
DISPLAY INVISIBLE (-2475 3325);
FORCEPROP 2 LAST PATH I145
J 0
(-2275 3500);
DISPLAY 1.021277 (-2275 3500);
PAINT ORANGE (-2275 3500);
DISPLAY INVISIBLE (-2275 3500);
FORCEPROP 2 LAST $XRERR ?
J 0
(-2264 3425);
DISPLAY 0.638298 (-2264 3425);
PAINT MONO (-2264 3425);
DISPLAY INVISIBLE (-2264 3425);
FORCEPROP 2 LAST $XRERR ?
J 0
(-2264 3425);
DISPLAY 0.638298 (-2264 3425);
PAINT MONO (-2264 3425);
DISPLAY INVISIBLE (-2264 3425);
FORCEPROP 2 LAST $XRERR ?
J 0
(-2264 3425);
DISPLAY 0.638298 (-2264 3425);
PAINT MONO (-2264 3425);
DISPLAY INVISIBLE (-2264 3425);
FORCEPROP 2 LAST $XRERR ?
J 0
(-2264 3425);
DISPLAY 0.638298 (-2264 3425);
PAINT MONO (-2264 3425);
DISPLAY INVISIBLE (-2264 3425);
FORCEPROP 2 LAST $XRERR ?
J 0
(-2264 3425);
DISPLAY 0.638298 (-2264 3425);
PAINT MONO (-2264 3425);
DISPLAY INVISIBLE (-2264 3425);
FORCEPROP 2 LAST $XRERR ?
J 0
(-2264 3425);
DISPLAY 0.638298 (-2264 3425);
PAINT MONO (-2264 3425);
DISPLAY INVISIBLE (-2264 3425);
FORCEADD OFFPAGE..2
(-2450 3725);
FORCEPROP 2 LAST $XR0 186 
J 0
(-2261 3725);
DISPLAY 0.638298 (-2261 3725);
PAINT MONO (-2261 3725);
FORCEPROP 2 LAST CDS_LIB mstr_standard
J 0
(-2450 3725);
PAINT ORANGE (-2450 3725);
DISPLAY INVISIBLE (-2450 3725);
FORCEPROP 1 LAST OFFPAGE TRUE
J 0
(-2125 3600);
DISPLAY 1.170213 (-2125 3600);
PAINT GREEN (-2125 3600);
DISPLAY INVISIBLE (-2125 3600);
FORCEPROP 1 LAST COMMENT_BODY TRUE
J 0
(-2495 3630);
DISPLAY 1.170213 (-2495 3630);
PAINT GREEN (-2495 3630);
DISPLAY INVISIBLE (-2495 3630);
FORCEPROP 2 LAST PATH I147
J 0
(-2275 3800);
DISPLAY 1.021277 (-2275 3800);
PAINT ORANGE (-2275 3800);
DISPLAY INVISIBLE (-2275 3800);
FORCEADD OFFPAGE..4
(-2450 3825);
FORCEPROP 2 LAST $XR0 221 
J 0
(-2264 3825);
DISPLAY 0.638298 (-2264 3825);
PAINT MONO (-2264 3825);
FORCEPROP 2 LAST $XR1 222 
J 0
(-2144 3825);
DISPLAY 0.638298 (-2144 3825);
PAINT MONO (-2144 3825);
FORCEPROP 2 LAST CDS_LIB mstr_standard
J 0
(-2450 3825);
PAINT ORANGE (-2450 3825);
DISPLAY INVISIBLE (-2450 3825);
FORCEPROP 1 LAST OFFPAGE TRUE
J 0
(-2125 3700);
DISPLAY 0.872340 (-2125 3700);
PAINT GREEN (-2125 3700);
DISPLAY INVISIBLE (-2125 3700);
FORCEPROP 1 LAST COMMENT_BODY TRUE
J 0
(-2475 3725);
DISPLAY 0.872340 (-2475 3725);
PAINT GREEN (-2475 3725);
DISPLAY INVISIBLE (-2475 3725);
FORCEPROP 2 LAST PATH I148
J 0
(-2275 3900);
DISPLAY 1.021277 (-2275 3900);
PAINT ORANGE (-2275 3900);
DISPLAY INVISIBLE (-2275 3900);
FORCEADD OFFPAGE..4
(-2450 3875);
FORCEPROP 2 LAST $XR0 121 
J 0
(-2264 3875);
DISPLAY 0.638298 (-2264 3875);
PAINT MONO (-2264 3875);
FORCEPROP 2 LAST $XR1 133 
J 0
(-2144 3875);
DISPLAY 0.638298 (-2144 3875);
PAINT MONO (-2144 3875);
FORCEPROP 2 LAST CDS_LIB mstr_standard
J 0
(-2450 3875);
PAINT ORANGE (-2450 3875);
DISPLAY INVISIBLE (-2450 3875);
FORCEPROP 1 LAST OFFPAGE TRUE
J 0
(-2125 3750);
DISPLAY 1.170213 (-2125 3750);
PAINT GREEN (-2125 3750);
DISPLAY INVISIBLE (-2125 3750);
FORCEPROP 1 LAST COMMENT_BODY TRUE
J 0
(-2475 3775);
DISPLAY 1.170213 (-2475 3775);
PAINT GREEN (-2475 3775);
DISPLAY INVISIBLE (-2475 3775);
FORCEPROP 2 LAST PATH I149
J 0
(-2275 3950);
DISPLAY 1.021277 (-2275 3950);
PAINT ORANGE (-2275 3950);
DISPLAY INVISIBLE (-2275 3950);
FORCEADD OFFPAGE..2
(-2450 2625);
FORCEPROP 2 LAST $XR0 181 
J 0
(-2261 2625);
DISPLAY 0.638298 (-2261 2625);
PAINT MONO (-2261 2625);
FORCEPROP 2 LAST CDS_LIB mstr_standard
J 0
(-2450 2625);
PAINT ORANGE (-2450 2625);
DISPLAY INVISIBLE (-2450 2625);
FORCEPROP 1 LAST OFFPAGE TRUE
J 0
(-2125 2500);
DISPLAY 1.170213 (-2125 2500);
PAINT GREEN (-2125 2500);
DISPLAY INVISIBLE (-2125 2500);
FORCEPROP 1 LAST COMMENT_BODY TRUE
J 0
(-2495 2530);
DISPLAY 1.170213 (-2495 2530);
PAINT GREEN (-2495 2530);
DISPLAY INVISIBLE (-2495 2530);
FORCEPROP 2 LAST PATH I151
J 0
(-2275 2700);
DISPLAY 1.021277 (-2275 2700);
PAINT ORANGE (-2275 2700);
DISPLAY INVISIBLE (-2275 2700);
FORCEADD OFFPAGE..2
R 2
(-6425 4225);
FORCEPROP 2 LAST $XR0 102 
J 0
(-6680 4225);
DISPLAY 0.638298 (-6680 4225);
PAINT MONO (-6680 4225);
FORCEPROP 2 LAST CDS_LIB mstr_standard
J 0
(-6425 4225);
PAINT MONO (-6425 4225);
DISPLAY INVISIBLE (-6425 4225);
FORCEPROP 1 LAST OFFPAGE TRUE
J 2
(-6750 4100);
DISPLAY 1.170213 (-6750 4100);
PAINT GREEN (-6750 4100);
DISPLAY INVISIBLE (-6750 4100);
FORCEPROP 1 LAST COMMENT_BODY TRUE
J 2
(-6380 4130);
DISPLAY 1.170213 (-6380 4130);
PAINT GREEN (-6380 4130);
DISPLAY INVISIBLE (-6380 4130);
FORCEPROP 2 LAST PATH I156
J 0
(-6375 4300);
DISPLAY 1.021277 (-6375 4300);
PAINT ORANGE (-6375 4300);
DISPLAY INVISIBLE (-6375 4300);
FORCEADD OFFPAGE..4
(-2450 2425);
FORCEPROP 2 LAST $XR0 192 
J 0
(-2264 2425);
DISPLAY 0.638298 (-2264 2425);
PAINT MONO (-2264 2425);
FORCEPROP 2 LAST CDS_LIB mstr_standard
J 0
(-2450 2425);
PAINT MONO (-2450 2425);
DISPLAY INVISIBLE (-2450 2425);
FORCEPROP 1 LAST OFFPAGE TRUE
J 0
(-2125 2300);
DISPLAY 1.170213 (-2125 2300);
PAINT GREEN (-2125 2300);
DISPLAY INVISIBLE (-2125 2300);
FORCEPROP 1 LAST COMMENT_BODY TRUE
J 0
(-2475 2325);
DISPLAY 1.170213 (-2475 2325);
PAINT GREEN (-2475 2325);
DISPLAY INVISIBLE (-2475 2325);
FORCEPROP 2 LAST PATH I157
J 0
(-2275 2500);
DISPLAY 1.021277 (-2275 2500);
PAINT ORANGE (-2275 2500);
DISPLAY INVISIBLE (-2275 2500);
FORCEADD OFFPAGE..2
(-2450 4125);
FORCEPROP 2 LAST $XR0 198 
J 0
(-2261 4125);
DISPLAY 0.638298 (-2261 4125);
PAINT MONO (-2261 4125);
FORCEPROP 2 LAST CDS_LIB mstr_standard
J 0
(-2450 4125);
PAINT MONO (-2450 4125);
DISPLAY INVISIBLE (-2450 4125);
FORCEPROP 1 LAST OFFPAGE TRUE
J 0
(-2125 4000);
DISPLAY 1.170213 (-2125 4000);
PAINT GREEN (-2125 4000);
DISPLAY INVISIBLE (-2125 4000);
FORCEPROP 1 LAST COMMENT_BODY TRUE
J 0
(-2495 4030);
DISPLAY 1.170213 (-2495 4030);
PAINT GREEN (-2495 4030);
DISPLAY INVISIBLE (-2495 4030);
FORCEPROP 2 LAST PATH I158
J 0
(-2275 4200);
DISPLAY 1.021277 (-2275 4200);
PAINT ORANGE (-2275 4200);
DISPLAY INVISIBLE (-2275 4200);
FORCEADD OFFPAGE..2
R 2
(-6425 2225);
FORCEPROP 2 LAST $XR0 218 
J 0
(-6680 2225);
DISPLAY 0.638298 (-6680 2225);
PAINT MONO (-6680 2225);
FORCEPROP 2 LAST CDS_LIB mstr_standard
J 0
(-6425 2225);
PAINT MONO (-6425 2225);
DISPLAY INVISIBLE (-6425 2225);
FORCEPROP 1 LAST OFFPAGE TRUE
J 2
(-6750 2100);
DISPLAY 0.872340 (-6750 2100);
PAINT GREEN (-6750 2100);
DISPLAY INVISIBLE (-6750 2100);
FORCEPROP 1 LAST COMMENT_BODY TRUE
J 2
(-6380 2130);
DISPLAY 0.872340 (-6380 2130);
PAINT GREEN (-6380 2130);
DISPLAY INVISIBLE (-6380 2130);
FORCEPROP 2 LAST PATH I160
J 0
(-6375 2300);
DISPLAY 1.021277 (-6375 2300);
PAINT ORANGE (-6375 2300);
DISPLAY INVISIBLE (-6375 2300);
FORCEADD OFFPAGE..2
R 2
(-6425 2975);
FORCEPROP 2 LAST $XR0 226 
J 0
(-6680 2975);
DISPLAY 0.638298 (-6680 2975);
PAINT MONO (-6680 2975);
FORCEPROP 2 LAST CDS_LIB mstr_standard
J 0
(-6425 2975);
PAINT MONO (-6425 2975);
DISPLAY INVISIBLE (-6425 2975);
FORCEPROP 1 LAST OFFPAGE TRUE
J 2
(-6750 2850);
DISPLAY 1.170213 (-6750 2850);
PAINT GREEN (-6750 2850);
DISPLAY INVISIBLE (-6750 2850);
FORCEPROP 1 LAST COMMENT_BODY TRUE
J 2
(-6380 2880);
DISPLAY 1.170213 (-6380 2880);
PAINT GREEN (-6380 2880);
DISPLAY INVISIBLE (-6380 2880);
FORCEPROP 2 LAST PATH I161
J 0
(-6375 3050);
DISPLAY 1.021277 (-6375 3050);
PAINT ORANGE (-6375 3050);
DISPLAY INVISIBLE (-6375 3050);
FORCEADD OFFPAGE..2
R 2
(-6425 2275);
FORCEPROP 2 LAST $XR0 215 
J 0
(-6680 2275);
DISPLAY 0.638298 (-6680 2275);
PAINT MONO (-6680 2275);
FORCEPROP 2 LAST CDS_LIB mstr_standard
J 0
(-6425 2275);
PAINT MONO (-6425 2275);
DISPLAY INVISIBLE (-6425 2275);
FORCEPROP 1 LAST OFFPAGE TRUE
J 2
(-6750 2150);
DISPLAY 1.170213 (-6750 2150);
PAINT GREEN (-6750 2150);
DISPLAY INVISIBLE (-6750 2150);
FORCEPROP 1 LAST COMMENT_BODY TRUE
J 2
(-6380 2180);
DISPLAY 1.170213 (-6380 2180);
PAINT GREEN (-6380 2180);
DISPLAY INVISIBLE (-6380 2180);
FORCEPROP 2 LAST PATH I162
J 0
(-6375 2350);
DISPLAY 1.021277 (-6375 2350);
PAINT ORANGE (-6375 2350);
DISPLAY INVISIBLE (-6375 2350);
FORCEADD OFFPAGE..1
(-6425 3025);
FORCEPROP 2 LAST $XR0 170 
J 0
(-6677 3025);
DISPLAY 0.638298 (-6677 3025);
PAINT MONO (-6677 3025);
FORCEPROP 2 LAST CDS_LIB mstr_standard
J 0
(-6425 3025);
PAINT MONO (-6425 3025);
DISPLAY INVISIBLE (-6425 3025);
FORCEPROP 1 LAST OFFPAGE TRUE
J 0
(-6100 2900);
DISPLAY 0.872340 (-6100 2900);
PAINT GREEN (-6100 2900);
DISPLAY INVISIBLE (-6100 2900);
FORCEPROP 1 LAST COMMENT_BODY TRUE
J 0
(-6300 2925);
DISPLAY 0.872340 (-6300 2925);
PAINT GREEN (-6300 2925);
DISPLAY INVISIBLE (-6300 2925);
FORCEPROP 2 LAST PATH I163
J 0
(-6375 3100);
DISPLAY 1.021277 (-6375 3100);
PAINT ORANGE (-6375 3100);
DISPLAY INVISIBLE (-6375 3100);
FORCEADD OFFPAGE..5
(-6425 2875);
FORCEPROP 2 LAST $XR0 170 
J 0
(-6680 2875);
DISPLAY 0.638298 (-6680 2875);
PAINT MONO (-6680 2875);
FORCEPROP 2 LAST CDS_LIB mstr_standard
J 0
(-6425 2875);
PAINT MONO (-6425 2875);
DISPLAY INVISIBLE (-6425 2875);
FORCEPROP 1 LAST OFFPAGE TRUE
J 0
(-6100 2750);
DISPLAY 0.872340 (-6100 2750);
PAINT GREEN (-6100 2750);
DISPLAY INVISIBLE (-6100 2750);
FORCEPROP 1 LAST COMMENT_BODY TRUE
J 0
(-6325 2800);
DISPLAY 0.872340 (-6325 2800);
PAINT GREEN (-6325 2800);
DISPLAY INVISIBLE (-6325 2800);
FORCEPROP 2 LAST PATH I164
J 0
(-6375 2950);
DISPLAY 1.021277 (-6375 2950);
PAINT ORANGE (-6375 2950);
DISPLAY INVISIBLE (-6375 2950);
FORCEADD OFFPAGE..4
R 2
(-6425 3175);
FORCEPROP 2 LAST $XR0 121 
J 0
(-6677 3175);
DISPLAY 0.638298 (-6677 3175);
PAINT MONO (-6677 3175);
FORCEPROP 2 LAST $XR1 133 
J 0
(-6797 3175);
DISPLAY 0.638298 (-6797 3175);
PAINT MONO (-6797 3175);
FORCEPROP 2 LAST CDS_LIB mstr_standard
J 0
(-6425 3175);
PAINT MONO (-6425 3175);
DISPLAY INVISIBLE (-6425 3175);
FORCEPROP 1 LAST OFFPAGE TRUE
J 2
(-6750 3050);
DISPLAY 1.170213 (-6750 3050);
PAINT GREEN (-6750 3050);
DISPLAY INVISIBLE (-6750 3050);
FORCEPROP 1 LAST COMMENT_BODY TRUE
J 2
(-6400 3075);
DISPLAY 1.170213 (-6400 3075);
PAINT GREEN (-6400 3075);
DISPLAY INVISIBLE (-6400 3075);
FORCEPROP 2 LAST PATH I165
J 0
(-6375 3250);
DISPLAY 1.021277 (-6375 3250);
PAINT ORANGE (-6375 3250);
DISPLAY INVISIBLE (-6375 3250);
FORCEADD RES..1
(-1425 2675);
FORCEPROP 1 LAST LOCATION R2R6
J 0
(-1600 2700);
DISPLAY 0.617021 (-1600 2700);
PAINT AQUA (-1600 2700);
FORCEPROP 1 LAST PART_NUMBER G21497-048
J 0
(-1100 2625);
DISPLAY 0.617021 (-1100 2625);
PAINT BLUE (-1100 2625);
FORCEPROP 1 LAST VALUE 51
J 2
(-1450 2625);
DISPLAY 0.617021 (-1450 2625);
PAINT SKYBLUE (-1450 2625);
FORCEPROP 1 LAST TOLERANCE 5.0%
J 0
(-1375 2625);
DISPLAY 0.617021 (-1375 2625);
PAINT SKYBLUE (-1375 2625);
FORCEPROP 1 LAST WATTAGE 1/16W
J 2
(-1125 2625);
DISPLAY 0.617021 (-1125 2625);
PAINT SKYBLUE (-1125 2625);
FORCEPROP 1 LASTPIN (-1525 2675) $PN 1
J 0
(-1513 2687);
DISPLAY 0.787234 (-1513 2687);
PAINT ORANGE (-1513 2687);
FORCEPROP 1 LASTPIN (-1325 2675) $PN 2
J 0
(-1363 2687);
DISPLAY 0.787234 (-1363 2687);
PAINT ORANGE (-1363 2687);
FORCEPROP 1 LAST MATERIAL CHIP
J 0
(-1425 2525);
DISPLAY 0.617021 (-1425 2525);
PAINT SKYBLUE (-1425 2525);
DISPLAY INVISIBLE (-1425 2525);
FORCEPROP 2 LAST ROOM CPLD
J 0
(-1100 2675);
PAINT MONO (-1100 2675);
DISPLAY INVISIBLE (-1100 2675);
FORCEPROP 1 LAST PATH I166
J 0
(-1475 2825);
DISPLAY 0.978723 (-1475 2825);
PAINT WHITE (-1475 2825);
DISPLAY INVISIBLE (-1475 2825);
FORCEPROP 2 LAST CDS_LOCATION R2R6
J 0
(-1600 2700);
DISPLAY 0.617021 (-1600 2700);
PAINT AQUA (-1600 2700);
DISPLAY INVISIBLE (-1600 2700);
FORCEPROP 2 LAST CDS_LIB mstr_discrete
J 0
(-1425 2675);
PAINT MONO (-1425 2675);
DISPLAY INVISIBLE (-1425 2675);
FORCEPROP 1 LAST PACK_TYPE 0402
J 0
(-1175 2525);
DISPLAY 0.617021 (-1175 2525);
PAINT SKYBLUE (-1175 2525);
DISPLAY INVISIBLE (-1175 2525);
FORCEPROP 2 LAST SEC 1
J 0
(-1475 2875);
PAINT MONO (-1475 2875);
DISPLAY INVISIBLE (-1475 2875);
FORCEPROP 2 LAST SEC_TYPE 0402
J 0
(-1475 2875);
DISPLAY 1.021277 (-1475 2875);
PAINT ORANGE (-1475 2875);
DISPLAY INVISIBLE (-1475 2875);
FORCEADD OFFPAGE..2
(-850 2675);
FORCEPROP 2 LASTPIN (-900 2675) SIG_NAME SGPIO_BMC_DIN
J 2
(-910 2685);
DISPLAY 0.617021 (-910 2685);
PAINT ORANGE (-910 2685);
FORCEPROP 2 LAST $XR0 144 
J 0
(-661 2675);
DISPLAY 0.638298 (-661 2675);
PAINT MONO (-661 2675);
FORCEPROP 2 LAST CDS_LIB mstr_standard
J 0
(-850 2675);
PAINT MONO (-850 2675);
DISPLAY INVISIBLE (-850 2675);
FORCEPROP 1 LAST OFFPAGE TRUE
J 0
(-525 2550);
DISPLAY 1.170213 (-525 2550);
PAINT GREEN (-525 2550);
DISPLAY INVISIBLE (-525 2550);
FORCEPROP 1 LAST COMMENT_BODY TRUE
J 0
(-895 2580);
DISPLAY 1.170213 (-895 2580);
PAINT GREEN (-895 2580);
DISPLAY INVISIBLE (-895 2580);
FORCEPROP 2 LAST PATH I167
J 0
(-675 2750);
DISPLAY 1.021277 (-675 2750);
PAINT ORANGE (-675 2750);
DISPLAY INVISIBLE (-675 2750);
FORCEADD OFFPAGE..4
R 2
(-6425 3275);
FORCEPROP 2 LAST $XR0 200 
J 0
(-6677 3275);
DISPLAY 0.638298 (-6677 3275);
PAINT MONO (-6677 3275);
FORCEPROP 2 LAST CDS_LIB mstr_standard
J 0
(-6425 3275);
PAINT MONO (-6425 3275);
DISPLAY INVISIBLE (-6425 3275);
FORCEPROP 1 LAST OFFPAGE TRUE
J 2
(-6750 3150);
DISPLAY 1.170213 (-6750 3150);
PAINT GREEN (-6750 3150);
DISPLAY INVISIBLE (-6750 3150);
FORCEPROP 1 LAST COMMENT_BODY TRUE
J 2
(-6400 3175);
DISPLAY 1.170213 (-6400 3175);
PAINT GREEN (-6400 3175);
DISPLAY INVISIBLE (-6400 3175);
FORCEPROP 2 LAST PATH I168
J 0
(-6375 3350);
DISPLAY 1.021277 (-6375 3350);
PAINT ORANGE (-6375 3350);
DISPLAY INVISIBLE (-6375 3350);
FORCEADD OFFPAGE..4
R 2
(-6425 3125);
FORCEPROP 2 LAST $XR0 119 
J 0
(-6677 3125);
DISPLAY 0.638298 (-6677 3125);
PAINT MONO (-6677 3125);
FORCEPROP 2 LAST $XR1 125 
J 0
(-6797 3125);
DISPLAY 0.638298 (-6797 3125);
PAINT MONO (-6797 3125);
FORCEPROP 2 LAST $XR2 147 
J 0
(-6917 3125);
DISPLAY 0.638298 (-6917 3125);
PAINT MONO (-6917 3125);
FORCEPROP 2 LAST CDS_LIB mstr_standard
J 0
(-6425 3125);
PAINT MONO (-6425 3125);
DISPLAY INVISIBLE (-6425 3125);
FORCEPROP 1 LAST OFFPAGE TRUE
J 2
(-6750 3000);
DISPLAY 1.170213 (-6750 3000);
PAINT GREEN (-6750 3000);
DISPLAY INVISIBLE (-6750 3000);
FORCEPROP 1 LAST COMMENT_BODY TRUE
J 2
(-6400 3025);
DISPLAY 1.170213 (-6400 3025);
PAINT GREEN (-6400 3025);
DISPLAY INVISIBLE (-6400 3025);
FORCEPROP 2 LAST PATH I169
J 0
(-6375 3200);
DISPLAY 1.021277 (-6375 3200);
PAINT ORANGE (-6375 3200);
DISPLAY INVISIBLE (-6375 3200);
FORCEADD OFFPAGE..4
(-2450 3675);
FORCEPROP 2 LAST $XR0 238 
J 0
(-2264 3675);
DISPLAY 0.638298 (-2264 3675);
PAINT MONO (-2264 3675);
FORCEPROP 2 LAST CDS_LIB mstr_standard
J 0
(-2450 3675);
PAINT ORANGE (-2450 3675);
DISPLAY INVISIBLE (-2450 3675);
FORCEPROP 1 LAST OFFPAGE TRUE
J 0
(-2125 3550);
DISPLAY 1.170213 (-2125 3550);
PAINT GREEN (-2125 3550);
DISPLAY INVISIBLE (-2125 3550);
FORCEPROP 1 LAST COMMENT_BODY TRUE
J 0
(-2475 3575);
DISPLAY 1.170213 (-2475 3575);
PAINT GREEN (-2475 3575);
DISPLAY INVISIBLE (-2475 3575);
FORCEPROP 2 LAST PATH I17
J 0
(-1800 3725);
DISPLAY 1.021277 (-1800 3725);
PAINT ORANGE (-1800 3725);
DISPLAY INVISIBLE (-1800 3725);
FORCEADD OFFPAGE..4
(-850 3325);
FORCEPROP 2 LAST $XR0 120 
J 0
(-664 3325);
DISPLAY 0.638298 (-664 3325);
PAINT MONO (-664 3325);
FORCEPROP 2 LAST $XR1 147 
J 0
(-544 3325);
DISPLAY 0.638298 (-544 3325);
PAINT MONO (-544 3325);
FORCEPROP 2 LAST CDS_LIB mstr_standard
J 0
(-850 3325);
PAINT MONO (-850 3325);
DISPLAY INVISIBLE (-850 3325);
FORCEPROP 1 LAST OFFPAGE TRUE
J 0
(-525 3200);
DISPLAY 1.170213 (-525 3200);
PAINT GREEN (-525 3200);
DISPLAY INVISIBLE (-525 3200);
FORCEPROP 1 LAST COMMENT_BODY TRUE
J 0
(-875 3225);
DISPLAY 1.170213 (-875 3225);
PAINT GREEN (-875 3225);
DISPLAY INVISIBLE (-875 3225);
FORCEPROP 2 LAST PATH I170
J 0
(-675 3400);
DISPLAY 1.021277 (-675 3400);
PAINT ORANGE (-675 3400);
DISPLAY INVISIBLE (-675 3400);
FORCEADD P3V3_STBY..1
(-1375 3750);
FORCEPROP 3 LASTPIN (-1375 3700) SIG_NAME P3V3_STBY\g
J 0
(-1365 3710);
DISPLAY 0.659574 (-1365 3710);
PAINT MONO (-1365 3710);
DISPLAY INVISIBLE (-1365 3710);
FORCEPROP 1 LAST VOLTAGE 3.3V
J 0
(-1420 3707);
DISPLAY 0.340426 (-1420 3707);
PAINT SKYBLUE (-1420 3707);
DISPLAY INVISIBLE (-1420 3707);
FORCEPROP 1 LAST HDL_POWER P3V3_STBY
J 0
(-1675 3625);
DISPLAY 0.872340 (-1675 3625);
PAINT ORANGE (-1675 3625);
DISPLAY INVISIBLE (-1675 3625);
FORCEPROP 1 LAST PATH I171
J 0
(-1330 3752);
DISPLAY 0.340426 (-1330 3752);
PAINT GREEN (-1330 3752);
DISPLAY INVISIBLE (-1330 3752);
FORCEPROP 1 LAST BODY_TYPE PLUMBING
J 0
(-1420 3707);
DISPLAY 0.340426 (-1420 3707);
PAINT GREEN (-1420 3707);
DISPLAY INVISIBLE (-1420 3707);
FORCEPROP 2 LAST CDS_LIB mstr_symbols
J 0
(-1375 3750);
PAINT MONO (-1375 3750);
DISPLAY INVISIBLE (-1375 3750);
FORCEPROP 1 LAST SIZE 1B
J 0
(-1330 3772);
DISPLAY 0.340426 (-1330 3772);
PAINT GREEN (-1330 3772);
DISPLAY INVISIBLE (-1330 3772);
FORCEADD RES..2
R 2
(-1375 3550);
FORCEPROP 1 LAST LOCATION R2R7
J 2
(-1420 3675);
DISPLAY 0.617021 (-1420 3675);
PAINT AQUA (-1420 3675);
FORCEPROP 1 LAST PART_NUMBER G21796-072
J 2
(-1415 3425);
DISPLAY 0.617021 (-1415 3425);
PAINT BLUE (-1415 3425);
FORCEPROP 1 LAST VALUE 4.75K
J 2
(-1420 3625);
DISPLAY 0.617021 (-1420 3625);
PAINT SKYBLUE (-1420 3625);
FORCEPROP 1 LAST TOLERANCE 1%
J 2
(-1420 3575);
DISPLAY 0.617021 (-1420 3575);
PAINT SKYBLUE (-1420 3575);
FORCEPROP 1 LAST MATERIAL CHIP
J 2
(-1415 3475);
DISPLAY 0.617021 (-1415 3475);
PAINT SKYBLUE (-1415 3475);
FORCEPROP 1 LAST WATTAGE 1/16W
J 2
(-1415 3525);
DISPLAY 0.617021 (-1415 3525);
PAINT SKYBLUE (-1415 3525);
FORCEPROP 1 LAST PACK_TYPE 0402
J 2
(-1415 3375);
DISPLAY 0.617021 (-1415 3375);
PAINT SKYBLUE (-1415 3375);
FORCEPROP 1 LASTPIN (-1375 3650) $PN 1
J 2
(-1380 3612);
DISPLAY 0.787234 (-1380 3612);
PAINT ORANGE (-1380 3612);
FORCEPROP 1 LASTPIN (-1375 3450) $PN 2
J 2
(-1380 3460);
DISPLAY 0.787234 (-1380 3460);
PAINT ORANGE (-1380 3460);
FORCEPROP 2 LAST ROOM CPLD
J 0
(-1400 3650);
PAINT MONO (-1400 3650);
DISPLAY INVISIBLE (-1400 3650);
FORCEPROP 1 LAST PATH I172
J 2
(-1425 3725);
DISPLAY 0.978723 (-1425 3725);
PAINT WHITE (-1425 3725);
DISPLAY INVISIBLE (-1425 3725);
FORCEPROP 2 LAST CDS_LOCATION R2R7
J 2
(-1420 3675);
DISPLAY 0.617021 (-1420 3675);
PAINT AQUA (-1420 3675);
DISPLAY INVISIBLE (-1420 3675);
FORCEPROP 2 LAST BOM_COST CPLD
J 0
(-1400 3700);
PAINT MONO (-1400 3700);
DISPLAY INVISIBLE (-1400 3700);
FORCEPROP 2 LAST SIGNAL_MODEL DEFAULT_RESISTOR_47000OHM_2_1
J 0
(-1425 3775);
PAINT MONO (-1425 3775);
DISPLAY INVISIBLE (-1425 3775);
FORCEPROP 2 LAST CDS_LIB mstr_discrete
J 0
(-1375 3550);
PAINT MONO (-1375 3550);
DISPLAY INVISIBLE (-1375 3550);
FORCEPROP 2 LAST SEC 1
J 0
(-1425 3775);
PAINT MONO (-1425 3775);
DISPLAY INVISIBLE (-1425 3775);
FORCEPROP 2 LAST SEC_TYPE 0402
J 0
(-1425 3775);
DISPLAY 1.021277 (-1425 3775);
PAINT ORANGE (-1425 3775);
DISPLAY INVISIBLE (-1425 3775);
FORCEADD OFFPAGE..2
(-2450 4075);
FORCEPROP 2 LAST $XR0 120 
J 0
(-2261 4075);
DISPLAY 0.638298 (-2261 4075);
PAINT MONO (-2261 4075);
FORCEPROP 2 LAST $XR1 146 
J 0
(-2141 4075);
DISPLAY 0.638298 (-2141 4075);
PAINT MONO (-2141 4075);
FORCEPROP 2 LAST CDS_LIB mstr_standard
J 0
(-2450 4075);
PAINT MONO (-2450 4075);
DISPLAY INVISIBLE (-2450 4075);
FORCEPROP 1 LAST OFFPAGE TRUE
J 0
(-2125 3950);
DISPLAY 1.170213 (-2125 3950);
PAINT GREEN (-2125 3950);
DISPLAY INVISIBLE (-2125 3950);
FORCEPROP 1 LAST COMMENT_BODY TRUE
J 0
(-2495 3980);
DISPLAY 1.170213 (-2495 3980);
PAINT GREEN (-2495 3980);
DISPLAY INVISIBLE (-2495 3980);
FORCEPROP 2 LAST PATH I173
J 0
(-2275 4150);
DISPLAY 1.021277 (-2275 4150);
PAINT ORANGE (-2275 4150);
DISPLAY INVISIBLE (-2275 4150);
FORCEADD OFFPAGE..2
R 2
(-6425 3625);
FORCEPROP 2 LAST $XR0 146 
J 0
(-6680 3625);
DISPLAY 0.638298 (-6680 3625);
PAINT MONO (-6680 3625);
FORCEPROP 2 LAST $XR1 151 
J 0
(-6800 3625);
DISPLAY 0.638298 (-6800 3625);
PAINT MONO (-6800 3625);
FORCEPROP 2 LAST $XR2 119 
J 0
(-6800 3625);
DISPLAY 0.638298 (-6800 3625);
PAINT MONO (-6800 3625);
FORCEPROP 2 LAST CDS_LIB mstr_standard
J 0
(-6425 3625);
PAINT MONO (-6425 3625);
DISPLAY INVISIBLE (-6425 3625);
FORCEPROP 1 LAST OFFPAGE TRUE
J 2
(-6750 3500);
DISPLAY 1.170213 (-6750 3500);
PAINT GREEN (-6750 3500);
DISPLAY INVISIBLE (-6750 3500);
FORCEPROP 1 LAST COMMENT_BODY TRUE
J 2
(-6380 3530);
DISPLAY 1.170213 (-6380 3530);
PAINT GREEN (-6380 3530);
DISPLAY INVISIBLE (-6380 3530);
FORCEPROP 2 LAST PATH I174
J 0
(-6375 3700);
DISPLAY 1.021277 (-6375 3700);
PAINT ORANGE (-6375 3700);
DISPLAY INVISIBLE (-6375 3700);
FORCEADD OFFPAGE..2
R 2
(-6425 1875);
FORCEPROP 2 LAST $XR0 120 
J 0
(-6680 1875);
DISPLAY 0.638298 (-6680 1875);
PAINT MONO (-6680 1875);
FORCEPROP 2 LAST $XR1 145 
J 0
(-6800 1875);
DISPLAY 0.638298 (-6800 1875);
PAINT MONO (-6800 1875);
FORCEPROP 2 LAST CDS_LIB mstr_standard
J 0
(-6425 1875);
PAINT ORANGE (-6425 1875);
DISPLAY INVISIBLE (-6425 1875);
FORCEPROP 1 LAST OFFPAGE TRUE
J 2
(-6750 1750);
DISPLAY 1.170213 (-6750 1750);
PAINT GREEN (-6750 1750);
DISPLAY INVISIBLE (-6750 1750);
FORCEPROP 1 LAST COMMENT_BODY TRUE
J 2
(-6380 1780);
DISPLAY 1.170213 (-6380 1780);
PAINT GREEN (-6380 1780);
DISPLAY INVISIBLE (-6380 1780);
FORCEPROP 2 LAST PATH I175
J 0
(-6375 1950);
DISPLAY 1.021277 (-6375 1950);
PAINT ORANGE (-6375 1950);
DISPLAY INVISIBLE (-6375 1950);
FORCEADD OFFPAGE..2
(-2450 2375);
FORCEPROP 2 LAST $XR0 201 
J 0
(-2231 2375);
DISPLAY 0.638298 (-2231 2375);
PAINT MONO (-2231 2375);
FORCEPROP 2 LAST CDS_LIB mstr_standard
J 0
(-2450 2375);
PAINT ORANGE (-2450 2375);
DISPLAY INVISIBLE (-2450 2375);
FORCEPROP 1 LAST OFFPAGE TRUE
J 0
(-2125 2250);
DISPLAY 1.170213 (-2125 2250);
PAINT GREEN (-2125 2250);
DISPLAY INVISIBLE (-2125 2250);
FORCEPROP 1 LAST COMMENT_BODY TRUE
J 0
(-2495 2280);
DISPLAY 1.170213 (-2495 2280);
PAINT GREEN (-2495 2280);
DISPLAY INVISIBLE (-2495 2280);
FORCEPROP 2 LAST PATH I176
J 0
(-2275 2450);
DISPLAY 1.021277 (-2275 2450);
PAINT ORANGE (-2275 2450);
DISPLAY INVISIBLE (-2275 2450);
FORCEADD OFFPAGE..2
R 2
(-6425 2925);
FORCEPROP 2 LAST $XR0 223 
J 0
(-6680 2925);
DISPLAY 0.638298 (-6680 2925);
PAINT MONO (-6680 2925);
FORCEPROP 2 LAST CDS_LIB mstr_standard
J 0
(-6425 2925);
PAINT ORANGE (-6425 2925);
DISPLAY INVISIBLE (-6425 2925);
FORCEPROP 1 LAST OFFPAGE TRUE
J 2
(-6750 2800);
DISPLAY 1.170213 (-6750 2800);
PAINT GREEN (-6750 2800);
DISPLAY INVISIBLE (-6750 2800);
FORCEPROP 1 LAST COMMENT_BODY TRUE
J 2
(-6380 2830);
DISPLAY 1.170213 (-6380 2830);
PAINT GREEN (-6380 2830);
DISPLAY INVISIBLE (-6380 2830);
FORCEPROP 2 LAST PATH I177
J 0
(-6375 3000);
DISPLAY 1.021277 (-6375 3000);
PAINT ORANGE (-6375 3000);
DISPLAY INVISIBLE (-6375 3000);
FORCEADD OFFPAGE..4
R 2
(-6425 2025);
FORCEPROP 2 LAST $XR0 213 
J 0
(-6677 2025);
DISPLAY 0.638298 (-6677 2025);
PAINT MONO (-6677 2025);
FORCEPROP 2 LAST CDS_LIB mstr_standard
J 0
(-6425 2025);
PAINT ORANGE (-6425 2025);
DISPLAY INVISIBLE (-6425 2025);
FORCEPROP 1 LAST OFFPAGE TRUE
J 2
(-6750 1900);
DISPLAY 1.170213 (-6750 1900);
PAINT GREEN (-6750 1900);
DISPLAY INVISIBLE (-6750 1900);
FORCEPROP 1 LAST COMMENT_BODY TRUE
J 2
(-6400 1925);
DISPLAY 1.170213 (-6400 1925);
PAINT GREEN (-6400 1925);
DISPLAY INVISIBLE (-6400 1925);
FORCEPROP 2 LAST PATH I178
J 0
(-6375 2100);
DISPLAY 1.021277 (-6375 2100);
PAINT ORANGE (-6375 2100);
DISPLAY INVISIBLE (-6375 2100);
FORCEADD OFFPAGE..2
R 2
(-6425 1275);
FORCEPROP 2 LAST $XR0 206 
J 0
(-6680 1275);
DISPLAY 0.638298 (-6680 1275);
PAINT MONO (-6680 1275);
FORCEPROP 2 LAST CDS_LIB mstr_standard
J 0
(-6425 1275);
PAINT ORANGE (-6425 1275);
DISPLAY INVISIBLE (-6425 1275);
FORCEPROP 1 LAST OFFPAGE TRUE
J 2
(-6750 1150);
DISPLAY 1.170213 (-6750 1150);
PAINT GREEN (-6750 1150);
DISPLAY INVISIBLE (-6750 1150);
FORCEPROP 1 LAST COMMENT_BODY TRUE
J 2
(-6380 1180);
DISPLAY 1.170213 (-6380 1180);
PAINT GREEN (-6380 1180);
DISPLAY INVISIBLE (-6380 1180);
FORCEPROP 2 LAST PATH I179
J 0
(-6375 1350);
DISPLAY 1.021277 (-6375 1350);
PAINT ORANGE (-6375 1350);
DISPLAY INVISIBLE (-6375 1350);
FORCEADD OFFPAGE..2
(-2450 3625);
FORCEPROP 2 LAST $XR0 189 
J 0
(-2261 3625);
DISPLAY 0.638298 (-2261 3625);
PAINT MONO (-2261 3625);
FORCEPROP 2 LAST CDS_LIB mstr_standard
J 2
(-2450 3625);
PAINT ORANGE (-2450 3625);
DISPLAY INVISIBLE (-2450 3625);
FORCEPROP 1 LAST OFFPAGE TRUE
J 0
(-2125 3500);
DISPLAY 1.170213 (-2125 3500);
PAINT GREEN (-2125 3500);
DISPLAY INVISIBLE (-2125 3500);
FORCEPROP 1 LAST COMMENT_BODY TRUE
J 0
(-2495 3530);
DISPLAY 1.170213 (-2495 3530);
PAINT GREEN (-2495 3530);
DISPLAY INVISIBLE (-2495 3530);
FORCEPROP 2 LAST PATH I18
J 0
(-2250 3675);
DISPLAY 1.021277 (-2250 3675);
PAINT ORANGE (-2250 3675);
DISPLAY INVISIBLE (-2250 3675);
FORCEADD OFFPAGE..4
R 2
(-6425 4075);
FORCEPROP 2 LAST $XR0 193 
J 0
(-6677 4075);
DISPLAY 0.638298 (-6677 4075);
PAINT MONO (-6677 4075);
FORCEPROP 2 LAST CDS_LIB mstr_standard
J 0
(-6425 4075);
PAINT ORANGE (-6425 4075);
DISPLAY INVISIBLE (-6425 4075);
FORCEPROP 1 LAST OFFPAGE TRUE
J 2
(-6750 3950);
DISPLAY 1.170213 (-6750 3950);
PAINT GREEN (-6750 3950);
DISPLAY INVISIBLE (-6750 3950);
FORCEPROP 1 LAST COMMENT_BODY TRUE
J 2
(-6400 3975);
DISPLAY 1.170213 (-6400 3975);
PAINT GREEN (-6400 3975);
DISPLAY INVISIBLE (-6400 3975);
FORCEPROP 2 LAST PATH I180
J 0
(-6375 4150);
DISPLAY 1.021277 (-6375 4150);
PAINT ORANGE (-6375 4150);
DISPLAY INVISIBLE (-6375 4150);
FORCEADD OFFPAGE..4
R 2
(-6425 3925);
FORCEPROP 2 LAST $XR0 194 
J 0
(-6707 3925);
DISPLAY 0.638298 (-6707 3925);
PAINT MONO (-6707 3925);
FORCEPROP 2 LAST CDS_LIB mstr_standard
J 0
(-6425 3925);
PAINT ORANGE (-6425 3925);
DISPLAY INVISIBLE (-6425 3925);
FORCEPROP 1 LAST OFFPAGE TRUE
J 2
(-6750 3800);
DISPLAY 1.170213 (-6750 3800);
PAINT GREEN (-6750 3800);
DISPLAY INVISIBLE (-6750 3800);
FORCEPROP 1 LAST COMMENT_BODY TRUE
J 2
(-6400 3825);
DISPLAY 1.170213 (-6400 3825);
PAINT GREEN (-6400 3825);
DISPLAY INVISIBLE (-6400 3825);
FORCEPROP 2 LAST PATH I181
J 0
(-6375 4000);
DISPLAY 1.021277 (-6375 4000);
PAINT ORANGE (-6375 4000);
DISPLAY INVISIBLE (-6375 4000);
FORCEADD OFFPAGE..2
R 2
(-6425 3775);
FORCEPROP 2 LAST $XR0 194 
J 0
(-6680 3775);
DISPLAY 0.638298 (-6680 3775);
PAINT MONO (-6680 3775);
FORCEPROP 2 LAST CDS_LIB mstr_standard
J 0
(-6425 3775);
PAINT ORANGE (-6425 3775);
DISPLAY INVISIBLE (-6425 3775);
FORCEPROP 1 LAST OFFPAGE TRUE
J 2
(-6750 3650);
DISPLAY 1.170213 (-6750 3650);
PAINT GREEN (-6750 3650);
DISPLAY INVISIBLE (-6750 3650);
FORCEPROP 1 LAST COMMENT_BODY TRUE
J 2
(-6380 3680);
DISPLAY 1.170213 (-6380 3680);
PAINT GREEN (-6380 3680);
DISPLAY INVISIBLE (-6380 3680);
FORCEPROP 2 LAST PATH I182
J 0
(-6375 3850);
DISPLAY 1.021277 (-6375 3850);
PAINT ORANGE (-6375 3850);
DISPLAY INVISIBLE (-6375 3850);
FORCEADD OFFPAGE..2
R 2
(-6425 3425);
FORCEPROP 2 LAST $XR0 193 
J 0
(-6680 3425);
DISPLAY 0.638298 (-6680 3425);
PAINT MONO (-6680 3425);
FORCEPROP 2 LAST CDS_LIB mstr_standard
J 0
(-6425 3425);
PAINT ORANGE (-6425 3425);
DISPLAY INVISIBLE (-6425 3425);
FORCEPROP 1 LAST OFFPAGE TRUE
J 2
(-6750 3300);
DISPLAY 1.170213 (-6750 3300);
PAINT GREEN (-6750 3300);
DISPLAY INVISIBLE (-6750 3300);
FORCEPROP 1 LAST COMMENT_BODY TRUE
J 2
(-6380 3330);
DISPLAY 1.170213 (-6380 3330);
PAINT GREEN (-6380 3330);
DISPLAY INVISIBLE (-6380 3330);
FORCEPROP 2 LAST PATH I183
J 0
(-6375 3500);
DISPLAY 1.021277 (-6375 3500);
PAINT ORANGE (-6375 3500);
DISPLAY INVISIBLE (-6375 3500);
FORCEADD RES..1
(-3200 4325);
FORCEPROP 1 LAST LOCATION R2R4
J 0
(-3250 4375);
DISPLAY 0.617021 (-3250 4375);
PAINT AQUA (-3250 4375);
FORCEPROP 1 LAST PART_NUMBER G21497-005
J 0
(-3250 4425);
DISPLAY 0.617021 (-3250 4425);
PAINT BLUE (-3250 4425);
FORCEPROP 1 LAST VALUE 0.0
J 2
(-3300 4425);
DISPLAY 0.617021 (-3300 4425);
PAINT SKYBLUE (-3300 4425);
FORCEPROP 1 LAST PACK_TYPE 0402
J 0
(-3500 4425);
DISPLAY 0.617021 (-3500 4425);
PAINT SKYBLUE (-3500 4425);
FORCEPROP 1 LAST MATERIAL CHIP
J 0
(-3000 4425);
DISPLAY 0.617021 (-3000 4425);
PAINT SKYBLUE (-3000 4425);
FORCEPROP 1 LASTPIN (-3300 4325) $PN 1
J 0
(-3288 4337);
DISPLAY 0.617021 (-3288 4337);
PAINT ORANGE (-3288 4337);
FORCEPROP 1 LASTPIN (-3100 4325) $PN 2
J 0
(-3138 4337);
DISPLAY 0.617021 (-3138 4337);
PAINT ORANGE (-3138 4337);
FORCEPROP 1 LAST TOLERANCE 5%
J 0
(-3200 4225);
DISPLAY 0.978723 (-3200 4225);
PAINT SKYBLUE (-3200 4225);
DISPLAY INVISIBLE (-3200 4225);
FORCEPROP 1 LAST WATTAGE 1/16W
J 2
(-3225 4175);
DISPLAY 0.978723 (-3225 4175);
PAINT SKYBLUE (-3225 4175);
DISPLAY INVISIBLE (-3225 4175);
FORCEPROP 0 LAST ROOM CPLD
J 0
(-3000 4525);
DISPLAY 1.021277 (-3000 4525);
PAINT ORANGE (-3000 4525);
DISPLAY INVISIBLE (-3000 4525);
FORCEPROP 1 LAST PATH I184
J 0
(-3250 4475);
DISPLAY 0.978723 (-3250 4475);
PAINT WHITE (-3250 4475);
DISPLAY INVISIBLE (-3250 4475);
FORCEPROP 2 LAST CDS_LOCATION R2R4
J 0
(-3250 4375);
DISPLAY 0.617021 (-3250 4375);
PAINT AQUA (-3250 4375);
DISPLAY INVISIBLE (-3250 4375);
FORCEPROP 2 LAST $SEC 1
J 0
(-3250 4525);
PAINT MONO (-3250 4525);
DISPLAY INVISIBLE (-3250 4525);
FORCEPROP 2 LAST CDS_SEC 1
J 0
(-3250 4525);
PAINT MONO (-3250 4525);
DISPLAY INVISIBLE (-3250 4525);
FORCEPROP 0 LAST BOM_COST CPLD
J 0
(-3000 4625);
DISPLAY 1.021277 (-3000 4625);
PAINT ORANGE (-3000 4625);
DISPLAY INVISIBLE (-3000 4625);
FORCEPROP 2 LAST CDS_LIB mstr_discrete
J 0
(-3200 4325);
PAINT ORANGE (-3200 4325);
DISPLAY INVISIBLE (-3200 4325);
FORCEADD OFFPAGE..4
(-2450 4275);
FORCEPROP 2 LASTPIN (-2500 4275) SIG_NAME PWRGD_P12V_MAIN
J 0
(-3085 4285);
DISPLAY 0.617021 (-3085 4285);
PAINT ORANGE (-3085 4285);
FORCEPROP 2 LAST $XR0 196 
J 0
(-2264 4275);
DISPLAY 0.638298 (-2264 4275);
PAINT MONO (-2264 4275);
FORCEPROP 2 LAST CDS_LIB mstr_standard
J 0
(-2450 4275);
PAINT ORANGE (-2450 4275);
DISPLAY INVISIBLE (-2450 4275);
FORCEPROP 1 LAST OFFPAGE TRUE
J 0
(-2125 4150);
DISPLAY 1.170213 (-2125 4150);
PAINT GREEN (-2125 4150);
DISPLAY INVISIBLE (-2125 4150);
FORCEPROP 1 LAST COMMENT_BODY TRUE
J 0
(-2475 4175);
DISPLAY 1.170213 (-2475 4175);
PAINT GREEN (-2475 4175);
DISPLAY INVISIBLE (-2475 4175);
FORCEPROP 2 LAST PATH I185
J 0
(-2275 4350);
DISPLAY 1.021277 (-2275 4350);
PAINT ORANGE (-2275 4350);
DISPLAY INVISIBLE (-2275 4350);
FORCEADD OFFPAGE..2
R 2
(-6425 3725);
FORCEPROP 2 LAST $XR0 102 
J 0
(-6680 3725);
DISPLAY 0.638298 (-6680 3725);
PAINT MONO (-6680 3725);
FORCEPROP 2 LAST CDS_LIB mstr_standard
J 0
(-6425 3725);
PAINT ORANGE (-6425 3725);
DISPLAY INVISIBLE (-6425 3725);
FORCEPROP 1 LAST OFFPAGE TRUE
J 2
(-6750 3600);
DISPLAY 1.170213 (-6750 3600);
PAINT GREEN (-6750 3600);
DISPLAY INVISIBLE (-6750 3600);
FORCEPROP 1 LAST COMMENT_BODY TRUE
J 2
(-6380 3630);
DISPLAY 1.170213 (-6380 3630);
PAINT GREEN (-6380 3630);
DISPLAY INVISIBLE (-6380 3630);
FORCEPROP 2 LAST PATH I186
J 0
(-6375 3800);
DISPLAY 1.021277 (-6375 3800);
PAINT ORANGE (-6375 3800);
DISPLAY INVISIBLE (-6375 3800);
FORCEADD OFFPAGE..2
R 2
(-6425 3475);
FORCEPROP 2 LAST $XR0 102 
J 0
(-6680 3475);
DISPLAY 0.638298 (-6680 3475);
PAINT MONO (-6680 3475);
FORCEPROP 2 LAST CDS_LIB mstr_standard
J 0
(-6425 3475);
PAINT ORANGE (-6425 3475);
DISPLAY INVISIBLE (-6425 3475);
FORCEPROP 1 LAST OFFPAGE TRUE
J 2
(-6750 3350);
DISPLAY 1.170213 (-6750 3350);
PAINT GREEN (-6750 3350);
DISPLAY INVISIBLE (-6750 3350);
FORCEPROP 1 LAST COMMENT_BODY TRUE
J 2
(-6380 3380);
DISPLAY 1.170213 (-6380 3380);
PAINT GREEN (-6380 3380);
DISPLAY INVISIBLE (-6380 3380);
FORCEPROP 2 LAST PATH I187
J 0
(-6375 3550);
DISPLAY 1.021277 (-6375 3550);
PAINT ORANGE (-6375 3550);
DISPLAY INVISIBLE (-6375 3550);
FORCEADD OFFPAGE..2
R 2
(-6425 1225);
FORCEPROP 2 LAST $XR0 104 
J 0
(-6680 1225);
DISPLAY 0.638298 (-6680 1225);
PAINT MONO (-6680 1225);
FORCEPROP 2 LAST CDS_LIB mstr_standard
J 0
(-6425 1225);
PAINT ORANGE (-6425 1225);
DISPLAY INVISIBLE (-6425 1225);
FORCEPROP 1 LAST OFFPAGE TRUE
J 2
(-6750 1100);
DISPLAY 1.170213 (-6750 1100);
PAINT GREEN (-6750 1100);
DISPLAY INVISIBLE (-6750 1100);
FORCEPROP 1 LAST COMMENT_BODY TRUE
J 2
(-6380 1130);
DISPLAY 1.170213 (-6380 1130);
PAINT GREEN (-6380 1130);
DISPLAY INVISIBLE (-6380 1130);
FORCEPROP 2 LAST PATH I188
J 0
(-6375 1300);
DISPLAY 1.021277 (-6375 1300);
PAINT ORANGE (-6375 1300);
DISPLAY INVISIBLE (-6375 1300);
FORCEADD OFFPAGE..2
(-2450 1925);
FORCEPROP 2 LAST $XR0 113 
J 0
(-2261 1925);
DISPLAY 0.638298 (-2261 1925);
PAINT MONO (-2261 1925);
FORCEPROP 2 LAST CDS_LIB mstr_standard
J 0
(-2450 1925);
PAINT ORANGE (-2450 1925);
DISPLAY INVISIBLE (-2450 1925);
FORCEPROP 1 LAST OFFPAGE TRUE
J 0
(-2125 1800);
DISPLAY 1.170213 (-2125 1800);
PAINT GREEN (-2125 1800);
DISPLAY INVISIBLE (-2125 1800);
FORCEPROP 1 LAST COMMENT_BODY TRUE
J 0
(-2495 1830);
DISPLAY 1.170213 (-2495 1830);
PAINT GREEN (-2495 1830);
DISPLAY INVISIBLE (-2495 1830);
FORCEPROP 2 LAST PATH I189
J 0
(-2275 2000);
DISPLAY 1.021277 (-2275 2000);
PAINT ORANGE (-2275 2000);
DISPLAY INVISIBLE (-2275 2000);
FORCEADD OFFPAGE..4
(-2450 3575);
FORCEPROP 2 LAST $XR0 189 
J 0
(-2264 3575);
DISPLAY 0.638298 (-2264 3575);
PAINT MONO (-2264 3575);
FORCEPROP 2 LAST CDS_LIB mstr_standard
J 0
(-2450 3575);
PAINT ORANGE (-2450 3575);
DISPLAY INVISIBLE (-2450 3575);
FORCEPROP 1 LAST OFFPAGE TRUE
J 0
(-2125 3450);
DISPLAY 1.170213 (-2125 3450);
PAINT GREEN (-2125 3450);
DISPLAY INVISIBLE (-2125 3450);
FORCEPROP 1 LAST COMMENT_BODY TRUE
J 0
(-2475 3475);
DISPLAY 1.170213 (-2475 3475);
PAINT GREEN (-2475 3475);
DISPLAY INVISIBLE (-2475 3475);
FORCEPROP 2 LAST PATH I19
J 0
(-2250 3625);
DISPLAY 1.021277 (-2250 3625);
PAINT ORANGE (-2250 3625);
DISPLAY INVISIBLE (-2250 3625);
FORCEADD OFFPAGE..2
(-2450 1875);
FORCEPROP 2 LAST $XR0 113 
J 0
(-2261 1875);
DISPLAY 0.638298 (-2261 1875);
PAINT MONO (-2261 1875);
FORCEPROP 2 LAST CDS_LIB mstr_standard
J 0
(-2450 1875);
PAINT ORANGE (-2450 1875);
DISPLAY INVISIBLE (-2450 1875);
FORCEPROP 1 LAST OFFPAGE TRUE
J 0
(-2125 1750);
DISPLAY 1.170213 (-2125 1750);
PAINT GREEN (-2125 1750);
DISPLAY INVISIBLE (-2125 1750);
FORCEPROP 1 LAST COMMENT_BODY TRUE
J 0
(-2495 1780);
DISPLAY 1.170213 (-2495 1780);
PAINT GREEN (-2495 1780);
DISPLAY INVISIBLE (-2495 1780);
FORCEPROP 2 LAST PATH I190
J 0
(-2275 1950);
DISPLAY 1.021277 (-2275 1950);
PAINT ORANGE (-2275 1950);
DISPLAY INVISIBLE (-2275 1950);
FORCEADD OFFPAGE..2
(-2450 1825);
FORCEPROP 2 LAST $XR0 113 
J 0
(-2261 1825);
DISPLAY 0.638298 (-2261 1825);
PAINT MONO (-2261 1825);
FORCEPROP 2 LAST CDS_LIB mstr_standard
J 0
(-2450 1825);
PAINT ORANGE (-2450 1825);
DISPLAY INVISIBLE (-2450 1825);
FORCEPROP 1 LAST OFFPAGE TRUE
J 0
(-2125 1700);
DISPLAY 1.170213 (-2125 1700);
PAINT GREEN (-2125 1700);
DISPLAY INVISIBLE (-2125 1700);
FORCEPROP 1 LAST COMMENT_BODY TRUE
J 0
(-2495 1730);
DISPLAY 1.170213 (-2495 1730);
PAINT GREEN (-2495 1730);
DISPLAY INVISIBLE (-2495 1730);
FORCEPROP 2 LAST PATH I191
J 0
(-2275 1900);
DISPLAY 1.021277 (-2275 1900);
PAINT ORANGE (-2275 1900);
DISPLAY INVISIBLE (-2275 1900);
FORCEADD OFFPAGE..2
(-2450 1775);
FORCEPROP 2 LAST $XR0 113 
J 0
(-2261 1775);
DISPLAY 0.638298 (-2261 1775);
PAINT MONO (-2261 1775);
FORCEPROP 2 LAST CDS_LIB mstr_standard
J 0
(-2450 1775);
PAINT ORANGE (-2450 1775);
DISPLAY INVISIBLE (-2450 1775);
FORCEPROP 1 LAST OFFPAGE TRUE
J 0
(-2125 1650);
DISPLAY 1.170213 (-2125 1650);
PAINT GREEN (-2125 1650);
DISPLAY INVISIBLE (-2125 1650);
FORCEPROP 1 LAST COMMENT_BODY TRUE
J 0
(-2495 1680);
DISPLAY 1.170213 (-2495 1680);
PAINT GREEN (-2495 1680);
DISPLAY INVISIBLE (-2495 1680);
FORCEPROP 2 LAST PATH I192
J 0
(-2275 1850);
DISPLAY 1.021277 (-2275 1850);
PAINT ORANGE (-2275 1850);
DISPLAY INVISIBLE (-2275 1850);
FORCEADD RES..2
(-7225 2675);
FORCEPROP 1 LAST LOCATION R7D42
J 0
(-7180 2800);
DISPLAY 0.617021 (-7180 2800);
PAINT AQUA (-7180 2800);
FORCEPROP 1 LAST PART_NUMBER G21796-072
J 0
(-7185 2550);
DISPLAY 0.617021 (-7185 2550);
PAINT BLUE (-7185 2550);
FORCEPROP 1 LAST VALUE 4.75K
J 0
(-7180 2750);
DISPLAY 0.617021 (-7180 2750);
PAINT SKYBLUE (-7180 2750);
FORCEPROP 1 LAST TOLERANCE 1%
J 0
(-7180 2700);
DISPLAY 0.617021 (-7180 2700);
PAINT SKYBLUE (-7180 2700);
FORCEPROP 1 LAST PACK_TYPE 0402
J 0
(-7185 2500);
DISPLAY 0.617021 (-7185 2500);
PAINT SKYBLUE (-7185 2500);
FORCEPROP 1 LAST MATERIAL CHIP
J 0
(-7185 2600);
DISPLAY 0.617021 (-7185 2600);
PAINT SKYBLUE (-7185 2600);
FORCEPROP 1 LAST WATTAGE 1/16W
J 0
(-7185 2650);
DISPLAY 0.617021 (-7185 2650);
PAINT SKYBLUE (-7185 2650);
FORCEPROP 1 LASTPIN (-7225 2775) $PN 1
J 0
(-7220 2737);
DISPLAY 0.617021 (-7220 2737);
PAINT ORANGE (-7220 2737);
FORCEPROP 1 LASTPIN (-7225 2575) $PN 2
J 0
(-7220 2585);
DISPLAY 0.617021 (-7220 2585);
PAINT ORANGE (-7220 2585);
FORCEPROP 0 LAST ROOM CPLD
J 0
(-7175 2900);
DISPLAY 1.021277 (-7175 2900);
PAINT ORANGE (-7175 2900);
DISPLAY INVISIBLE (-7175 2900);
FORCEPROP 1 LAST PATH I193
J 0
(-7175 2850);
DISPLAY 0.978723 (-7175 2850);
PAINT WHITE (-7175 2850);
DISPLAY INVISIBLE (-7175 2850);
FORCEPROP 2 LAST SEC 1
J 0
(-7175 2900);
DISPLAY 0.680851 (-7175 2900);
PAINT MONO (-7175 2900);
DISPLAY INVISIBLE (-7175 2900);
FORCEPROP 2 LAST CDS_LIB mstr_discrete
J 0
(-7225 2675);
PAINT ORANGE (-7225 2675);
DISPLAY INVISIBLE (-7225 2675);
FORCEPROP 2 LAST SEC_TYPE 0402
J 0
(-7175 2900);
DISPLAY 1.021277 (-7175 2900);
PAINT ORANGE (-7175 2900);
DISPLAY INVISIBLE (-7175 2900);
FORCEADD P3V3_STBY..1
(-7225 2900);
FORCEPROP 3 LASTPIN (-7225 2850) SIG_NAME P3V3_STBY\g
J 0
(-7215 2860);
DISPLAY 0.659574 (-7215 2860);
PAINT MONO (-7215 2860);
DISPLAY INVISIBLE (-7215 2860);
FORCEPROP 1 LAST VOLTAGE 3.3V
J 0
(-7270 2857);
DISPLAY 0.340426 (-7270 2857);
PAINT SKYBLUE (-7270 2857);
DISPLAY INVISIBLE (-7270 2857);
FORCEPROP 1 LAST HDL_POWER P3V3_STBY
J 0
(-7525 2775);
DISPLAY 0.872340 (-7525 2775);
PAINT ORANGE (-7525 2775);
DISPLAY INVISIBLE (-7525 2775);
FORCEPROP 1 LAST PATH I194
J 0
(-7180 2902);
DISPLAY 0.340426 (-7180 2902);
PAINT GREEN (-7180 2902);
DISPLAY INVISIBLE (-7180 2902);
FORCEPROP 1 LAST BODY_TYPE PLUMBING
J 0
(-7270 2857);
DISPLAY 0.340426 (-7270 2857);
PAINT GREEN (-7270 2857);
DISPLAY INVISIBLE (-7270 2857);
FORCEPROP 1 LAST SIZE 1B
J 0
(-7180 2922);
DISPLAY 0.340426 (-7180 2922);
PAINT GREEN (-7180 2922);
DISPLAY INVISIBLE (-7180 2922);
FORCEPROP 2 LAST CDS_LIB mstr_symbols
J 0
(-7225 2900);
PAINT ORANGE (-7225 2900);
DISPLAY INVISIBLE (-7225 2900);
FORCEADD OFFPAGE..2
(-2450 4325);
FORCEPROP 2 LAST $XR0 89 
J 0
(-2261 4325);
DISPLAY 0.638298 (-2261 4325);
PAINT MONO (-2261 4325);
FORCEPROP 2 LAST $XR1 156 
J 0
(-2171 4325);
DISPLAY 0.638298 (-2171 4325);
PAINT MONO (-2171 4325);
FORCEPROP 2 LAST $XR2 157 
J 0
(-2051 4325);
DISPLAY 0.638298 (-2051 4325);
PAINT MONO (-2051 4325);
FORCEPROP 2 LAST $XR3 120 
J 0
(-1931 4325);
DISPLAY 0.638298 (-1931 4325);
PAINT MONO (-1931 4325);
FORCEPROP 2 LAST CDS_LIB mstr_standard
J 0
(-2450 4325);
PAINT ORANGE (-2450 4325);
DISPLAY INVISIBLE (-2450 4325);
FORCEPROP 1 LAST OFFPAGE TRUE
J 0
(-2125 4200);
DISPLAY 1.170213 (-2125 4200);
PAINT GREEN (-2125 4200);
DISPLAY INVISIBLE (-2125 4200);
FORCEPROP 1 LAST COMMENT_BODY TRUE
J 0
(-2495 4230);
DISPLAY 1.170213 (-2495 4230);
PAINT GREEN (-2495 4230);
DISPLAY INVISIBLE (-2495 4230);
FORCEPROP 2 LAST PATH I2
J 0
(-2250 4375);
DISPLAY 1.021277 (-2250 4375);
PAINT ORANGE (-2250 4375);
DISPLAY INVISIBLE (-2250 4375);
FORCEADD OFFPAGE..2
(-2450 3375);
FORCEPROP 2 LAST $XR0 120 
J 0
(-2261 3375);
DISPLAY 0.638298 (-2261 3375);
PAINT MONO (-2261 3375);
FORCEPROP 2 LAST $XR1 148 
J 0
(-2141 3375);
DISPLAY 0.638298 (-2141 3375);
PAINT MONO (-2141 3375);
FORCEPROP 2 LAST CDS_LIB mstr_standard
J 0
(-2450 3375);
PAINT ORANGE (-2450 3375);
DISPLAY INVISIBLE (-2450 3375);
FORCEPROP 1 LAST OFFPAGE TRUE
J 0
(-2125 3250);
DISPLAY 1.170213 (-2125 3250);
PAINT GREEN (-2125 3250);
DISPLAY INVISIBLE (-2125 3250);
FORCEPROP 1 LAST COMMENT_BODY TRUE
J 0
(-2495 3280);
DISPLAY 1.170213 (-2495 3280);
PAINT GREEN (-2495 3280);
DISPLAY INVISIBLE (-2495 3280);
FORCEPROP 2 LAST PATH I22
J 0
(-2250 3425);
DISPLAY 1.021277 (-2250 3425);
PAINT ORANGE (-2250 3425);
DISPLAY INVISIBLE (-2250 3425);
FORCEADD OFFPAGE..4
(-2450 3225);
FORCEPROP 2 LAST $XR0 192 
J 0
(-2264 3225);
DISPLAY 0.638298 (-2264 3225);
PAINT MONO (-2264 3225);
FORCEPROP 2 LAST CDS_LIB mstr_standard
J 0
(-2450 3225);
PAINT ORANGE (-2450 3225);
DISPLAY INVISIBLE (-2450 3225);
FORCEPROP 1 LAST OFFPAGE TRUE
J 0
(-2125 3100);
DISPLAY 1.170213 (-2125 3100);
PAINT GREEN (-2125 3100);
DISPLAY INVISIBLE (-2125 3100);
FORCEPROP 1 LAST COMMENT_BODY TRUE
J 0
(-2475 3125);
DISPLAY 1.170213 (-2475 3125);
PAINT GREEN (-2475 3125);
DISPLAY INVISIBLE (-2475 3125);
FORCEPROP 2 LAST PATH I24
J 0
(-2250 3275);
DISPLAY 1.021277 (-2250 3275);
PAINT ORANGE (-2250 3275);
DISPLAY INVISIBLE (-2250 3275);
FORCEADD OFFPAGE..4
(-2450 3125);
FORCEPROP 2 LAST $XR0 189 
J 0
(-2264 3125);
DISPLAY 0.638298 (-2264 3125);
PAINT MONO (-2264 3125);
FORCEPROP 2 LAST CDS_LIB mstr_standard
J 2
(-2450 3125);
PAINT ORANGE (-2450 3125);
DISPLAY INVISIBLE (-2450 3125);
FORCEPROP 1 LAST OFFPAGE TRUE
J 0
(-2125 3000);
DISPLAY 1.170213 (-2125 3000);
PAINT GREEN (-2125 3000);
DISPLAY INVISIBLE (-2125 3000);
FORCEPROP 1 LAST COMMENT_BODY TRUE
J 0
(-2475 3025);
DISPLAY 1.170213 (-2475 3025);
PAINT GREEN (-2475 3025);
DISPLAY INVISIBLE (-2475 3025);
FORCEPROP 2 LAST PATH I26
J 0
(-2250 3175);
DISPLAY 1.021277 (-2250 3175);
PAINT ORANGE (-2250 3175);
DISPLAY INVISIBLE (-2250 3175);
FORCEADD OFFPAGE..4
(-2450 3075);
FORCEPROP 2 LAST $XR0 189 
J 0
(-2264 3075);
DISPLAY 0.638298 (-2264 3075);
PAINT MONO (-2264 3075);
FORCEPROP 2 LAST CDS_LIB mstr_standard
J 0
(-2450 3075);
PAINT ORANGE (-2450 3075);
DISPLAY INVISIBLE (-2450 3075);
FORCEPROP 1 LAST OFFPAGE TRUE
J 0
(-2125 2950);
DISPLAY 1.170213 (-2125 2950);
PAINT GREEN (-2125 2950);
DISPLAY INVISIBLE (-2125 2950);
FORCEPROP 1 LAST COMMENT_BODY TRUE
J 0
(-2475 2975);
DISPLAY 1.170213 (-2475 2975);
PAINT GREEN (-2475 2975);
DISPLAY INVISIBLE (-2475 2975);
FORCEPROP 2 LAST PATH I27
J 0
(-2250 3125);
DISPLAY 1.021277 (-2250 3125);
PAINT ORANGE (-2250 3125);
DISPLAY INVISIBLE (-2250 3125);
FORCEADD OFFPAGE..4
(-2450 2575);
FORCEPROP 2 LAST $XR0 167 
J 0
(-2264 2575);
DISPLAY 0.638298 (-2264 2575);
PAINT MONO (-2264 2575);
FORCEPROP 2 LAST $XR1 184 
J 0
(-2144 2575);
DISPLAY 0.638298 (-2144 2575);
PAINT MONO (-2144 2575);
FORCEPROP 2 LAST CDS_LIB mstr_standard
J 2
(-2450 2575);
PAINT ORANGE (-2450 2575);
DISPLAY INVISIBLE (-2450 2575);
FORCEPROP 1 LAST OFFPAGE TRUE
J 0
(-2125 2450);
DISPLAY 1.170213 (-2125 2450);
PAINT GREEN (-2125 2450);
DISPLAY INVISIBLE (-2125 2450);
FORCEPROP 1 LAST COMMENT_BODY TRUE
J 0
(-2475 2475);
DISPLAY 1.170213 (-2475 2475);
PAINT GREEN (-2475 2475);
DISPLAY INVISIBLE (-2475 2475);
FORCEPROP 2 LAST PATH I33
J 0
(-2250 2625);
DISPLAY 1.021277 (-2250 2625);
PAINT ORANGE (-2250 2625);
DISPLAY INVISIBLE (-2250 2625);
FORCEADD OFFPAGE..2
(-2450 2325);
FORCEPROP 2 LAST $XR0 181 
J 0
(-2261 2325);
DISPLAY 0.638298 (-2261 2325);
PAINT MONO (-2261 2325);
FORCEPROP 2 LAST CDS_LIB mstr_standard
J 0
(-2450 2325);
PAINT ORANGE (-2450 2325);
DISPLAY INVISIBLE (-2450 2325);
FORCEPROP 1 LAST OFFPAGE TRUE
J 0
(-2125 2200);
DISPLAY 1.170213 (-2125 2200);
PAINT GREEN (-2125 2200);
DISPLAY INVISIBLE (-2125 2200);
FORCEPROP 1 LAST COMMENT_BODY TRUE
J 0
(-2495 2230);
DISPLAY 1.170213 (-2495 2230);
PAINT GREEN (-2495 2230);
DISPLAY INVISIBLE (-2495 2230);
FORCEPROP 2 LAST PATH I38
J 0
(-2250 2375);
DISPLAY 1.021277 (-2250 2375);
PAINT ORANGE (-2250 2375);
DISPLAY INVISIBLE (-2250 2375);
FORCEADD OFFPAGE..4
(-2450 1675);
FORCEPROP 2 LAST $XR0 196 
J 0
(-2264 1675);
DISPLAY 0.638298 (-2264 1675);
PAINT MONO (-2264 1675);
FORCEPROP 2 LAST $XR1 200 
J 0
(-2144 1675);
DISPLAY 0.638298 (-2144 1675);
PAINT MONO (-2144 1675);
FORCEPROP 2 LAST $XR2 118 
J 0
(-2024 1675);
DISPLAY 0.638298 (-2024 1675);
PAINT MONO (-2024 1675);
FORCEPROP 2 LAST $XR3 157 
J 0
(-1904 1675);
DISPLAY 0.638298 (-1904 1675);
PAINT MONO (-1904 1675);
FORCEPROP 2 LAST $XR4 183 
J 0
(-1784 1675);
DISPLAY 0.638298 (-1784 1675);
PAINT MONO (-1784 1675);
FORCEPROP 2 LAST CDS_LIB mstr_standard
J 0
(-2450 1675);
PAINT ORANGE (-2450 1675);
DISPLAY INVISIBLE (-2450 1675);
FORCEPROP 1 LAST OFFPAGE TRUE
J 0
(-2125 1550);
DISPLAY 1.170213 (-2125 1550);
PAINT GREEN (-2125 1550);
DISPLAY INVISIBLE (-2125 1550);
FORCEPROP 1 LAST COMMENT_BODY TRUE
J 0
(-2475 1575);
DISPLAY 1.170213 (-2475 1575);
PAINT GREEN (-2475 1575);
DISPLAY INVISIBLE (-2475 1575);
FORCEPROP 2 LAST PATH I47
J 0
(-2250 1725);
DISPLAY 1.021277 (-2250 1725);
PAINT ORANGE (-2250 1725);
DISPLAY INVISIBLE (-2250 1725);
FORCEADD OFFPAGE..4
(-2450 1625);
FORCEPROP 2 LAST $XR0 192 
J 0
(-2264 1625);
DISPLAY 0.638298 (-2264 1625);
PAINT MONO (-2264 1625);
FORCEPROP 2 LAST CDS_LIB mstr_standard
J 2
(-2450 1625);
PAINT ORANGE (-2450 1625);
DISPLAY INVISIBLE (-2450 1625);
FORCEPROP 1 LAST OFFPAGE TRUE
J 0
(-2125 1500);
DISPLAY 1.170213 (-2125 1500);
PAINT GREEN (-2125 1500);
DISPLAY INVISIBLE (-2125 1500);
FORCEPROP 1 LAST COMMENT_BODY TRUE
J 0
(-2475 1525);
DISPLAY 1.170213 (-2475 1525);
PAINT GREEN (-2475 1525);
DISPLAY INVISIBLE (-2475 1525);
FORCEPROP 2 LAST PATH I49
J 0
(-2250 1675);
DISPLAY 1.021277 (-2250 1675);
PAINT ORANGE (-2250 1675);
DISPLAY INVISIBLE (-2250 1675);
FORCEADD LCMXO2_A..5
(-4475 2725);
FORCEPROP 1 LAST LOCATION U8D7
J 0
(-5049 4501);
DISPLAY 0.617021 (-5049 4501);
PAINT AQUA (-5049 4501);
FORCEPROP 1 LAST PART_NUMBER H63395-001
J 0
(-5025 975);
DISPLAY 0.617021 (-5025 975);
PAINT BLUE (-5025 975);
FORCEPROP 1 LAST MATERIAL IC
J 0
(-5049 4451);
DISPLAY 0.617021 (-5049 4451);
PAINT SKYBLUE (-5049 4451);
FORCEPROP 2 LASTPIN (-5075 3375) $PN G13
J 2
(-5085 3385);
DISPLAY 0.617021 (-5085 3385);
PAINT ORANGE (-5085 3385);
FORCEPROP 2 LASTPIN (-3875 3425) $PN C7
J 0
(-3865 3435);
DISPLAY 0.617021 (-3865 3435);
PAINT ORANGE (-3865 3435);
FORCEPROP 2 LASTPIN (-3875 3575) $PN A6
J 0
(-3865 3585);
DISPLAY 0.617021 (-3865 3585);
PAINT ORANGE (-3865 3585);
FORCEPROP 2 LASTPIN (-3875 3625) $PN C6
J 0
(-3865 3635);
DISPLAY 0.617021 (-3865 3635);
PAINT ORANGE (-3865 3635);
FORCEPROP 2 LASTPIN (-3875 3675) $PN E7
J 0
(-3865 3685);
DISPLAY 0.617021 (-3865 3685);
PAINT ORANGE (-3865 3685);
FORCEPROP 2 LASTPIN (-5075 4275) $PN E15
J 2
(-5085 4285);
DISPLAY 0.617021 (-5085 4285);
PAINT ORANGE (-5085 4285);
FORCEPROP 2 LASTPIN (-5075 4325) $PN D14
J 2
(-5085 4335);
DISPLAY 0.617021 (-5085 4335);
PAINT ORANGE (-5085 4335);
FORCEPROP 2 LASTPIN (-3875 1425) $PN C12
J 0
(-3865 1435);
DISPLAY 0.617021 (-3865 1435);
PAINT ORANGE (-3865 1435);
FORCEPROP 2 LASTPIN (-3875 2025) $PN B10
J 0
(-3865 2035);
DISPLAY 0.617021 (-3865 2035);
PAINT ORANGE (-3865 2035);
FORCEPROP 2 LASTPIN (-3875 2075) $PN C10
J 0
(-3865 2085);
DISPLAY 0.617021 (-3865 2085);
PAINT ORANGE (-3865 2085);
FORCEPROP 2 LASTPIN (-3875 2275) $PN E11
J 0
(-3865 2285);
DISPLAY 0.617021 (-3865 2285);
PAINT ORANGE (-3865 2285);
FORCEPROP 2 LASTPIN (-3875 2425) $PN B9
J 0
(-3865 2435);
DISPLAY 0.617021 (-3865 2435);
PAINT ORANGE (-3865 2435);
FORCEPROP 2 LASTPIN (-3875 1125) $PN C13
J 0
(-3865 1135);
DISPLAY 0.617021 (-3865 1135);
PAINT ORANGE (-3865 1135);
FORCEPROP 2 LASTPIN (-3875 1175) $PN A13
J 0
(-3865 1185);
DISPLAY 0.617021 (-3865 1185);
PAINT ORANGE (-3865 1185);
FORCEPROP 2 LASTPIN (-3875 1225) $PN A15
J 0
(-3865 1235);
DISPLAY 0.617021 (-3865 1235);
PAINT ORANGE (-3865 1235);
FORCEPROP 2 LASTPIN (-3875 1275) $PN B14
J 0
(-3865 1285);
DISPLAY 0.617021 (-3865 1285);
PAINT ORANGE (-3865 1285);
FORCEPROP 2 LASTPIN (-3875 1375) $PN B12
J 0
(-3865 1385);
DISPLAY 0.617021 (-3865 1385);
PAINT ORANGE (-3865 1385);
FORCEPROP 2 LASTPIN (-3875 1525) $PN A14
J 0
(-3865 1535);
DISPLAY 0.617021 (-3865 1535);
PAINT ORANGE (-3865 1535);
FORCEPROP 2 LASTPIN (-3875 1575) $PN B13
J 0
(-3865 1585);
DISPLAY 0.617021 (-3865 1585);
PAINT ORANGE (-3865 1585);
FORCEPROP 2 LASTPIN (-3875 1625) $PN A12
J 0
(-3865 1635);
DISPLAY 0.617021 (-3865 1635);
PAINT ORANGE (-3865 1635);
FORCEPROP 2 LASTPIN (-3875 1675) $PN B11
J 0
(-3865 1685);
DISPLAY 0.617021 (-3865 1685);
PAINT ORANGE (-3865 1685);
FORCEPROP 2 LASTPIN (-3875 1775) $PN D11
J 0
(-3865 1785);
DISPLAY 0.617021 (-3865 1785);
PAINT ORANGE (-3865 1785);
FORCEPROP 2 LASTPIN (-3875 1825) $PN F10
J 0
(-3865 1835);
DISPLAY 0.617021 (-3865 1835);
PAINT ORANGE (-3865 1835);
FORCEPROP 2 LASTPIN (-3875 1875) $PN C11
J 0
(-3865 1885);
DISPLAY 0.617021 (-3865 1885);
PAINT ORANGE (-3865 1885);
FORCEPROP 2 LASTPIN (-3875 1925) $PN A11
J 0
(-3865 1935);
DISPLAY 0.617021 (-3865 1935);
PAINT ORANGE (-3865 1935);
FORCEPROP 2 LASTPIN (-3875 2125) $PN E10
J 0
(-3865 2135);
DISPLAY 0.617021 (-3865 2135);
PAINT ORANGE (-3865 2135);
FORCEPROP 2 LASTPIN (-3875 2175) $PN D10
J 0
(-3865 2185);
DISPLAY 0.617021 (-3865 2185);
PAINT ORANGE (-3865 2185);
FORCEPROP 2 LASTPIN (-3875 2325) $PN F9
J 0
(-3865 2335);
DISPLAY 0.617021 (-3865 2335);
PAINT ORANGE (-3865 2335);
FORCEPROP 2 LASTPIN (-3875 2375) $PN A10
J 0
(-3865 2385);
DISPLAY 0.617021 (-3865 2385);
PAINT ORANGE (-3865 2385);
FORCEPROP 2 LASTPIN (-3875 2525) $PN C9
J 0
(-3865 2535);
DISPLAY 0.617021 (-3865 2535);
PAINT ORANGE (-3865 2535);
FORCEPROP 2 LASTPIN (-3875 2575) $PN A9
J 0
(-3865 2585);
DISPLAY 0.617021 (-3865 2585);
PAINT ORANGE (-3865 2585);
FORCEPROP 2 LASTPIN (-3875 2625) $PN D9
J 0
(-3865 2635);
DISPLAY 0.617021 (-3865 2635);
PAINT ORANGE (-3865 2635);
FORCEPROP 2 LASTPIN (-3875 2675) $PN F8
J 0
(-3865 2685);
DISPLAY 0.617021 (-3865 2685);
PAINT ORANGE (-3865 2685);
FORCEPROP 2 LASTPIN (-3875 2825) $PN E9
J 0
(-3865 2835);
DISPLAY 0.617021 (-3865 2835);
PAINT ORANGE (-3865 2835);
FORCEPROP 2 LASTPIN (-3875 2875) $PN D8
J 0
(-3865 2885);
DISPLAY 0.617021 (-3865 2885);
PAINT ORANGE (-3865 2885);
FORCEPROP 2 LASTPIN (-3875 2925) $PN A8
J 0
(-3865 2935);
DISPLAY 0.617021 (-3865 2935);
PAINT ORANGE (-3865 2935);
FORCEPROP 2 LASTPIN (-3875 2975) $PN C8
J 0
(-3865 2985);
DISPLAY 0.617021 (-3865 2985);
PAINT ORANGE (-3865 2985);
FORCEPROP 2 LASTPIN (-3875 3075) $PN B8
J 0
(-3865 3085);
DISPLAY 0.617021 (-3865 3085);
PAINT ORANGE (-3865 3085);
FORCEPROP 2 LASTPIN (-3875 3125) $PN A7
J 0
(-3865 3135);
DISPLAY 0.617021 (-3865 3135);
PAINT ORANGE (-3865 3135);
FORCEPROP 2 LASTPIN (-3875 3175) $PN E8
J 0
(-3865 3185);
DISPLAY 0.617021 (-3865 3185);
PAINT ORANGE (-3865 3185);
FORCEPROP 2 LASTPIN (-3875 3225) $PN F7
J 0
(-3865 3235);
DISPLAY 0.617021 (-3865 3235);
PAINT ORANGE (-3865 3235);
FORCEPROP 2 LASTPIN (-3875 3325) $PN D7
J 0
(-3865 3335);
DISPLAY 0.617021 (-3865 3335);
PAINT ORANGE (-3865 3335);
FORCEPROP 2 LASTPIN (-3875 3375) $PN E6
J 0
(-3865 3385);
DISPLAY 0.617021 (-3865 3385);
PAINT ORANGE (-3865 3385);
FORCEPROP 2 LASTPIN (-3875 3475) $PN B7
J 0
(-3865 3485);
DISPLAY 0.617021 (-3865 3485);
PAINT ORANGE (-3865 3485);
FORCEPROP 2 LASTPIN (-3875 3725) $PN D6
J 0
(-3865 3735);
DISPLAY 0.617021 (-3865 3735);
PAINT ORANGE (-3865 3735);
FORCEPROP 2 LASTPIN (-3875 3825) $PN B4
J 0
(-3865 3835);
DISPLAY 0.617021 (-3865 3835);
PAINT ORANGE (-3865 3835);
FORCEPROP 2 LASTPIN (-3875 3875) $PN A3
J 0
(-3865 3885);
DISPLAY 0.617021 (-3865 3885);
PAINT ORANGE (-3865 3885);
FORCEPROP 2 LASTPIN (-3875 3925) $PN B6
J 0
(-3865 3935);
DISPLAY 0.617021 (-3865 3935);
PAINT ORANGE (-3865 3935);
FORCEPROP 2 LASTPIN (-3875 3975) $PN A5
J 0
(-3865 3985);
DISPLAY 0.617021 (-3865 3985);
PAINT ORANGE (-3865 3985);
FORCEPROP 2 LASTPIN (-3875 4075) $PN C5
J 0
(-3865 4085);
DISPLAY 0.617021 (-3865 4085);
PAINT ORANGE (-3865 4085);
FORCEPROP 2 LASTPIN (-3875 4125) $PN A4
J 0
(-3865 4135);
DISPLAY 0.617021 (-3865 4135);
PAINT ORANGE (-3865 4135);
FORCEPROP 2 LASTPIN (-3875 4225) $PN B3
J 0
(-3865 4235);
DISPLAY 0.617021 (-3865 4235);
PAINT ORANGE (-3865 4235);
FORCEPROP 2 LASTPIN (-3875 4275) $PN B5
J 0
(-3865 4285);
DISPLAY 0.617021 (-3865 4285);
PAINT ORANGE (-3865 4285);
FORCEPROP 2 LASTPIN (-3875 4325) $PN C4
J 0
(-3865 4335);
DISPLAY 0.617021 (-3865 4335);
PAINT ORANGE (-3865 4335);
FORCEPROP 2 LASTPIN (-5075 1125) $PN R16
J 2
(-5085 1135);
DISPLAY 0.617021 (-5085 1135);
PAINT ORANGE (-5085 1135);
FORCEPROP 2 LASTPIN (-5075 1175) $PN P15
J 2
(-5085 1185);
DISPLAY 0.617021 (-5085 1185);
PAINT ORANGE (-5085 1185);
FORCEPROP 2 LASTPIN (-5075 1225) $PN N14
J 2
(-5085 1235);
DISPLAY 0.617021 (-5085 1235);
PAINT ORANGE (-5085 1235);
FORCEPROP 2 LASTPIN (-5075 1275) $PN N16
J 2
(-5085 1285);
DISPLAY 0.617021 (-5085 1285);
PAINT ORANGE (-5085 1285);
FORCEPROP 2 LASTPIN (-5075 1375) $PN P16
J 2
(-5085 1385);
DISPLAY 0.617021 (-5085 1385);
PAINT ORANGE (-5085 1385);
FORCEPROP 2 LASTPIN (-5075 1425) $PN N15
J 2
(-5085 1435);
DISPLAY 0.617021 (-5085 1435);
PAINT ORANGE (-5085 1435);
FORCEPROP 2 LASTPIN (-5075 1475) $PN M15
J 2
(-5085 1485);
DISPLAY 0.617021 (-5085 1485);
PAINT ORANGE (-5085 1485);
FORCEPROP 2 LASTPIN (-5075 1525) $PN M14
J 2
(-5085 1535);
DISPLAY 0.617021 (-5085 1535);
PAINT ORANGE (-5085 1535);
FORCEPROP 2 LASTPIN (-5075 1625) $PN L13
J 2
(-5085 1635);
DISPLAY 0.617021 (-5085 1635);
PAINT ORANGE (-5085 1635);
FORCEPROP 2 LASTPIN (-5075 1675) $PN K11
J 2
(-5085 1685);
DISPLAY 0.617021 (-5085 1685);
PAINT ORANGE (-5085 1685);
FORCEPROP 2 LASTPIN (-5075 1725) $PN M16
J 2
(-5085 1735);
DISPLAY 0.617021 (-5085 1735);
PAINT ORANGE (-5085 1735);
FORCEPROP 2 LASTPIN (-5075 1775) $PN L15
J 2
(-5085 1785);
DISPLAY 0.617021 (-5085 1785);
PAINT ORANGE (-5085 1785);
FORCEPROP 2 LASTPIN (-5075 1875) $PN K12
J 2
(-5085 1885);
DISPLAY 0.617021 (-5085 1885);
PAINT ORANGE (-5085 1885);
FORCEPROP 2 LASTPIN (-5075 1925) $PN K13
J 2
(-5085 1935);
DISPLAY 0.617021 (-5085 1935);
PAINT ORANGE (-5085 1935);
FORCEPROP 2 LASTPIN (-5075 1975) $PN L14
J 2
(-5085 1985);
DISPLAY 0.617021 (-5085 1985);
PAINT ORANGE (-5085 1985);
FORCEPROP 2 LASTPIN (-5075 2025) $PN L16
J 2
(-5085 2035);
DISPLAY 0.617021 (-5085 2035);
PAINT ORANGE (-5085 2035);
FORCEPROP 2 LASTPIN (-5075 2125) $PN L12
J 2
(-5085 2135);
DISPLAY 0.617021 (-5085 2135);
PAINT ORANGE (-5085 2135);
FORCEPROP 2 LASTPIN (-5075 2175) $PN J11
J 2
(-5085 2185);
DISPLAY 0.617021 (-5085 2185);
PAINT ORANGE (-5085 2185);
FORCEPROP 2 LASTPIN (-5075 2225) $PN K15
J 2
(-5085 2235);
DISPLAY 0.617021 (-5085 2235);
PAINT ORANGE (-5085 2235);
FORCEPROP 2 LASTPIN (-5075 2275) $PN K14
J 2
(-5085 2285);
DISPLAY 0.617021 (-5085 2285);
PAINT ORANGE (-5085 2285);
FORCEPROP 2 LASTPIN (-5075 2375) $PN J13
J 2
(-5085 2385);
DISPLAY 0.617021 (-5085 2385);
PAINT ORANGE (-5085 2385);
FORCEPROP 2 LASTPIN (-5075 2425) $PN H11
J 2
(-5085 2435);
DISPLAY 0.617021 (-5085 2435);
PAINT ORANGE (-5085 2435);
FORCEPROP 2 LASTPIN (-5075 2475) $PN K16
J 2
(-5085 2485);
DISPLAY 0.617021 (-5085 2485);
PAINT ORANGE (-5085 2485);
FORCEPROP 2 LASTPIN (-5075 2525) $PN J15
J 2
(-5085 2535);
DISPLAY 0.617021 (-5085 2535);
PAINT ORANGE (-5085 2535);
FORCEPROP 2 LASTPIN (-5075 2625) $PN J14
J 2
(-5085 2635);
DISPLAY 0.617021 (-5085 2635);
PAINT ORANGE (-5085 2635);
FORCEPROP 2 LASTPIN (-5075 2675) $PN J16
J 2
(-5085 2685);
DISPLAY 0.617021 (-5085 2685);
PAINT ORANGE (-5085 2685);
FORCEPROP 2 LASTPIN (-5075 2725) $PN H16
J 2
(-5085 2735);
DISPLAY 0.617021 (-5085 2735);
PAINT ORANGE (-5085 2735);
FORCEPROP 2 LASTPIN (-5075 2775) $PN H14
J 2
(-5085 2785);
DISPLAY 0.617021 (-5085 2785);
PAINT ORANGE (-5085 2785);
FORCEPROP 2 LASTPIN (-5075 2875) $PN J12
J 2
(-5085 2885);
DISPLAY 0.617021 (-5085 2885);
PAINT ORANGE (-5085 2885);
FORCEPROP 2 LASTPIN (-5075 2925) $PN H13
J 2
(-5085 2935);
DISPLAY 0.617021 (-5085 2935);
PAINT ORANGE (-5085 2935);
FORCEPROP 2 LASTPIN (-5075 2975) $PN H15
J 2
(-5085 2985);
DISPLAY 0.617021 (-5085 2985);
PAINT ORANGE (-5085 2985);
FORCEPROP 2 LASTPIN (-5075 3025) $PN G16
J 2
(-5085 3035);
DISPLAY 0.617021 (-5085 3035);
PAINT ORANGE (-5085 3035);
FORCEPROP 2 LASTPIN (-5075 3125) $PN H12
J 2
(-5085 3135);
DISPLAY 0.617021 (-5085 3135);
PAINT ORANGE (-5085 3135);
FORCEPROP 2 LASTPIN (-5075 3175) $PN G11
J 2
(-5085 3185);
DISPLAY 0.617021 (-5085 3185);
PAINT ORANGE (-5085 3185);
FORCEPROP 2 LASTPIN (-5075 3225) $PN G14
J 2
(-5085 3235);
DISPLAY 0.617021 (-5085 3235);
PAINT ORANGE (-5085 3235);
FORCEPROP 2 LASTPIN (-5075 3275) $PN G15
J 2
(-5085 3285);
DISPLAY 0.617021 (-5085 3285);
PAINT ORANGE (-5085 3285);
FORCEPROP 2 LASTPIN (-5075 3425) $PN F12
J 2
(-5085 3435);
DISPLAY 0.617021 (-5085 3435);
PAINT ORANGE (-5085 3435);
FORCEPROP 2 LASTPIN (-5075 3475) $PN F16
J 2
(-5085 3485);
DISPLAY 0.617021 (-5085 3485);
PAINT ORANGE (-5085 3485);
FORCEPROP 2 LASTPIN (-5075 3525) $PN F14
J 2
(-5085 3535);
DISPLAY 0.617021 (-5085 3535);
PAINT ORANGE (-5085 3535);
FORCEPROP 2 LASTPIN (-5075 3625) $PN G12
J 2
(-5085 3635);
DISPLAY 0.617021 (-5085 3635);
PAINT ORANGE (-5085 3635);
FORCEPROP 2 LASTPIN (-5075 3675) $PN F13
J 2
(-5085 3685);
DISPLAY 0.617021 (-5085 3685);
PAINT ORANGE (-5085 3685);
FORCEPROP 2 LASTPIN (-5075 3725) $PN F15
J 2
(-5085 3735);
DISPLAY 0.617021 (-5085 3735);
PAINT ORANGE (-5085 3735);
FORCEPROP 2 LASTPIN (-5075 3775) $PN E16
J 2
(-5085 3785);
DISPLAY 0.617021 (-5085 3785);
PAINT ORANGE (-5085 3785);
FORCEPROP 2 LASTPIN (-5075 3925) $PN D15
J 2
(-5085 3935);
DISPLAY 0.617021 (-5085 3935);
PAINT ORANGE (-5085 3935);
FORCEPROP 2 LASTPIN (-5075 3975) $PN C16
J 2
(-5085 3985);
DISPLAY 0.617021 (-5085 3985);
PAINT ORANGE (-5085 3985);
FORCEPROP 2 LASTPIN (-5075 4025) $PN E14
J 2
(-5085 4035);
DISPLAY 0.617021 (-5085 4035);
PAINT ORANGE (-5085 4035);
FORCEPROP 2 LASTPIN (-5075 4075) $PN D16
J 2
(-5085 4085);
DISPLAY 0.617021 (-5085 4085);
PAINT ORANGE (-5085 4085);
FORCEPROP 2 LASTPIN (-5075 4175) $PN B16
J 2
(-5085 4185);
DISPLAY 0.617021 (-5085 4185);
PAINT ORANGE (-5085 4185);
FORCEPROP 2 LASTPIN (-5075 4225) $PN C15
J 2
(-5085 4235);
DISPLAY 0.617021 (-5085 4235);
PAINT ORANGE (-5085 4235);
FORCEPROP 1 LAST PACK_TYPE 256BGA
J 0
(-5050 4550);
PAINT SKYBLUE (-5050 4550);
DISPLAY INVISIBLE (-5050 4550);
FORCEPROP 2 LAST ROOM CPLD
J 0
(-5025 4600);
DISPLAY 1.361702 (-5025 4600);
PAINT ORANGE (-5025 4600);
DISPLAY INVISIBLE (-5025 4600);
FORCEPROP 2 LAST SEC_TYPE 256BGA
J 0
(-5025 4550);
DISPLAY 1.021277 (-5025 4550);
PAINT ORANGE (-5025 4550);
DISPLAY INVISIBLE (-5025 4550);
FORCEPROP 2 LAST SEC 2
J 0
(-5025 4550);
DISPLAY 0.680851 (-5025 4550);
PAINT MONO (-5025 4550);
DISPLAY INVISIBLE (-5025 4550);
FORCEPROP 2 LAST CDS_LIB mstr_memory
J 0
(-4475 2725);
PAINT ORANGE (-4475 2725);
DISPLAY INVISIBLE (-4475 2725);
FORCEPROP 1 LAST CDS_LMAN_SYM_OUTLINE -550,1700,550,-1700
J 0
(-4475 2725);
DISPLAY 0.468085 (-4475 2725);
PAINT GREEN (-4475 2725);
DISPLAY INVISIBLE (-4475 2725);
FORCEPROP 1 LAST PATH I59
J 0
(-4100 4450);
PAINT GREEN (-4100 4450);
DISPLAY INVISIBLE (-4100 4450);
FORCEPROP 2 LAST CDS_LOCATION U8D7
J 0
(-5049 4501);
DISPLAY 0.617021 (-5049 4501);
PAINT AQUA (-5049 4501);
DISPLAY INVISIBLE (-5049 4501);
FORCEPROP 2 LAST BOM_COST CPLD
J 0
(-5025 4700);
DISPLAY 1.361702 (-5025 4700);
PAINT ORANGE (-5025 4700);
DISPLAY INVISIBLE (-5025 4700);
FORCEADD OFFPAGE..4
R 2
(-6425 3375);
FORCEPROP 2 LAST $XR0 92 
J 0
(-6676 3375);
DISPLAY 0.638298 (-6676 3375);
PAINT MONO (-6676 3375);
FORCEPROP 2 LAST CDS_LIB mstr_standard
J 0
(-6425 3375);
PAINT ORANGE (-6425 3375);
DISPLAY INVISIBLE (-6425 3375);
FORCEPROP 1 LAST OFFPAGE TRUE
J 2
(-6750 3250);
DISPLAY 1.170213 (-6750 3250);
PAINT GREEN (-6750 3250);
DISPLAY INVISIBLE (-6750 3250);
FORCEPROP 1 LAST COMMENT_BODY TRUE
J 2
(-6400 3275);
DISPLAY 1.170213 (-6400 3275);
PAINT GREEN (-6400 3275);
DISPLAY INVISIBLE (-6400 3275);
FORCEPROP 2 LAST PATH I84
J 0
(-6375 3450);
DISPLAY 1.021277 (-6375 3450);
PAINT ORANGE (-6375 3450);
DISPLAY INVISIBLE (-6375 3450);
FORCEADD OFFPAGE..2
R 2
(-6425 1175);
FORCEPROP 2 LAST $XR0 231 
J 0
(-6680 1175);
DISPLAY 0.638298 (-6680 1175);
PAINT MONO (-6680 1175);
FORCEPROP 2 LAST $XR1 232 
J 0
(-6800 1175);
DISPLAY 0.638298 (-6800 1175);
PAINT MONO (-6800 1175);
FORCEPROP 2 LAST CDS_LIB mstr_standard
J 0
(-6425 1175);
PAINT ORANGE (-6425 1175);
DISPLAY INVISIBLE (-6425 1175);
FORCEPROP 1 LAST OFFPAGE TRUE
J 2
(-6750 1050);
DISPLAY 1.170213 (-6750 1050);
PAINT GREEN (-6750 1050);
DISPLAY INVISIBLE (-6750 1050);
FORCEPROP 1 LAST COMMENT_BODY TRUE
J 2
(-6380 1080);
DISPLAY 1.170213 (-6380 1080);
PAINT GREEN (-6380 1080);
DISPLAY INVISIBLE (-6380 1080);
FORCEPROP 2 LAST PATH I87
J 0
(-6375 1250);
DISPLAY 1.021277 (-6375 1250);
PAINT ORANGE (-6375 1250);
DISPLAY INVISIBLE (-6375 1250);
FORCEADD OFFPAGE..2
R 2
(-6425 1125);
FORCEPROP 2 LAST $XR0 198 
J 0
(-6680 1125);
DISPLAY 0.638298 (-6680 1125);
PAINT MONO (-6680 1125);
FORCEPROP 2 LAST CDS_LIB mstr_standard
J 0
(-6425 1125);
PAINT ORANGE (-6425 1125);
DISPLAY INVISIBLE (-6425 1125);
FORCEPROP 1 LAST OFFPAGE TRUE
J 2
(-6750 1000);
DISPLAY 1.170213 (-6750 1000);
PAINT GREEN (-6750 1000);
DISPLAY INVISIBLE (-6750 1000);
FORCEPROP 1 LAST COMMENT_BODY TRUE
J 2
(-6380 1030);
DISPLAY 1.170213 (-6380 1030);
PAINT GREEN (-6380 1030);
DISPLAY INVISIBLE (-6380 1030);
FORCEPROP 2 LAST PATH I88
J 0
(-6375 1200);
DISPLAY 1.021277 (-6375 1200);
PAINT ORANGE (-6375 1200);
DISPLAY INVISIBLE (-6375 1200);
FORCEADD OFFPAGE..4
R 2
(-6425 1525);
FORCEPROP 2 LAST $XR0 55 
J 0
(-6646 1525);
DISPLAY 0.638298 (-6646 1525);
PAINT MONO (-6646 1525);
FORCEPROP 2 LAST $XR1 146 
J 0
(-6646 1525);
DISPLAY 0.638298 (-6646 1525);
PAINT MONO (-6646 1525);
FORCEPROP 2 LAST CDS_LIB mstr_standard
J 0
(-6425 1525);
PAINT ORANGE (-6425 1525);
DISPLAY INVISIBLE (-6425 1525);
FORCEPROP 1 LAST OFFPAGE TRUE
J 2
(-6750 1400);
DISPLAY 1.170213 (-6750 1400);
PAINT GREEN (-6750 1400);
DISPLAY INVISIBLE (-6750 1400);
FORCEPROP 1 LAST COMMENT_BODY TRUE
J 2
(-6400 1425);
DISPLAY 1.170213 (-6400 1425);
PAINT GREEN (-6400 1425);
DISPLAY INVISIBLE (-6400 1425);
FORCEPROP 2 LAST PATH I93
J 0
(-6375 1600);
DISPLAY 1.021277 (-6375 1600);
PAINT ORANGE (-6375 1600);
DISPLAY INVISIBLE (-6375 1600);
FORCEADD OFFPAGE..4
R 2
(-6425 1725);
FORCEPROP 2 LAST $XR0 92 
J 0
(-6676 1725);
DISPLAY 0.638298 (-6676 1725);
PAINT MONO (-6676 1725);
FORCEPROP 2 LAST CDS_LIB mstr_standard
J 0
(-6425 1725);
PAINT ORANGE (-6425 1725);
DISPLAY INVISIBLE (-6425 1725);
FORCEPROP 1 LAST OFFPAGE TRUE
J 2
(-6750 1600);
DISPLAY 1.170213 (-6750 1600);
PAINT GREEN (-6750 1600);
DISPLAY INVISIBLE (-6750 1600);
FORCEPROP 1 LAST COMMENT_BODY TRUE
J 2
(-6400 1625);
DISPLAY 1.170213 (-6400 1625);
PAINT GREEN (-6400 1625);
DISPLAY INVISIBLE (-6400 1625);
FORCEPROP 2 LAST PATH I95
J 0
(-6375 1800);
DISPLAY 1.021277 (-6375 1800);
PAINT ORANGE (-6375 1800);
DISPLAY INVISIBLE (-6375 1800);
FORCEADD OFFPAGE..2
R 2
(-6425 1675);
FORCEPROP 2 LAST $XR0 134 
J 0
(-6680 1675);
DISPLAY 0.638298 (-6680 1675);
PAINT MONO (-6680 1675);
FORCEPROP 2 LAST $XR1 145 
J 0
(-6800 1675);
DISPLAY 0.638298 (-6800 1675);
PAINT MONO (-6800 1675);
FORCEPROP 2 LAST $XR2 146 
J 0
(-6920 1675);
DISPLAY 0.638298 (-6920 1675);
PAINT MONO (-6920 1675);
FORCEPROP 2 LAST $XR3 184 
J 0
(-7040 1675);
DISPLAY 0.638298 (-7040 1675);
PAINT MONO (-7040 1675);
FORCEPROP 2 LAST CDS_LIB mstr_standard
J 0
(-6425 1675);
PAINT ORANGE (-6425 1675);
DISPLAY INVISIBLE (-6425 1675);
FORCEPROP 1 LAST OFFPAGE TRUE
J 2
(-6750 1550);
DISPLAY 1.170213 (-6750 1550);
PAINT GREEN (-6750 1550);
DISPLAY INVISIBLE (-6750 1550);
FORCEPROP 1 LAST COMMENT_BODY TRUE
J 2
(-6380 1580);
DISPLAY 1.170213 (-6380 1580);
PAINT GREEN (-6380 1580);
DISPLAY INVISIBLE (-6380 1580);
FORCEPROP 2 LAST PATH I96
J 0
(-6375 1750);
DISPLAY 1.021277 (-6375 1750);
PAINT ORANGE (-6375 1750);
DISPLAY INVISIBLE (-6375 1750);
FORCEADD OFFPAGE..2
R 2
(-6425 1775);
FORCEPROP 2 LAST $XR0 134 
J 0
(-6680 1775);
DISPLAY 0.638298 (-6680 1775);
PAINT MONO (-6680 1775);
FORCEPROP 2 LAST CDS_LIB mstr_standard
J 0
(-6425 1775);
PAINT ORANGE (-6425 1775);
DISPLAY INVISIBLE (-6425 1775);
FORCEPROP 1 LAST OFFPAGE TRUE
J 2
(-6750 1650);
DISPLAY 1.170213 (-6750 1650);
PAINT GREEN (-6750 1650);
DISPLAY INVISIBLE (-6750 1650);
FORCEPROP 1 LAST COMMENT_BODY TRUE
J 2
(-6380 1680);
DISPLAY 1.170213 (-6380 1680);
PAINT GREEN (-6380 1680);
DISPLAY INVISIBLE (-6380 1680);
FORCEPROP 2 LAST PATH I97
J 0
(-6375 1850);
DISPLAY 1.021277 (-6375 1850);
PAINT ORANGE (-6375 1850);
DISPLAY INVISIBLE (-6375 1850);
FORCEADD OFFPAGE..4
R 2
(-6425 1925);
FORCEPROP 2 LAST $XR0 94 
J 0
(-6646 1925);
DISPLAY 0.638298 (-6646 1925);
PAINT MONO (-6646 1925);
FORCEPROP 2 LAST $XR1 156 
J 0
(-6766 1925);
DISPLAY 0.638298 (-6766 1925);
PAINT MONO (-6766 1925);
FORCEPROP 2 LAST CDS_LIB mstr_standard
J 0
(-6425 1925);
PAINT ORANGE (-6425 1925);
DISPLAY INVISIBLE (-6425 1925);
FORCEPROP 1 LAST OFFPAGE TRUE
J 2
(-6750 1800);
DISPLAY 1.170213 (-6750 1800);
PAINT GREEN (-6750 1800);
DISPLAY INVISIBLE (-6750 1800);
FORCEPROP 1 LAST COMMENT_BODY TRUE
J 2
(-6400 1825);
DISPLAY 1.170213 (-6400 1825);
PAINT GREEN (-6400 1825);
DISPLAY INVISIBLE (-6400 1825);
FORCEPROP 2 LAST PATH I99
J 0
(-6375 2000);
DISPLAY 1.021277 (-6375 2000);
PAINT ORANGE (-6375 2000);
DISPLAY INVISIBLE (-6375 2000);
FORCEADD DESIGN_NOTE..1
(-4800 775);
FORCEPROP 0 LAST L1 SMBUS ADDRESSES:  0X80-0X86
J 0
(-5000 650);
DISPLAY 1.021277 (-5000 650);
PAINT ORANGE (-5000 650);
FORCEPROP 1 LAST COMMENT_BODY TRUE
J 0
(-4775 875);
DISPLAY 0.978723 (-4775 875);
PAINT ORANGE (-4775 875);
DISPLAY INVISIBLE (-4775 875);
FORCEPROP 2 LAST CDS_LIB mstr_symbols
J 0
(-4800 775);
PAINT ORANGE (-4800 775);
DISPLAY INVISIBLE (-4800 775);
FORCEADD CAD_NOTE..1
(-1775 2900);
FORCEPROP 0 LAST L1 PLACE THIS RESISTOR NEAR CPLD
J 0
(-1925 2750);
DISPLAY 1.021277 (-1925 2750);
PAINT ORANGE (-1925 2750);
FORCEPROP 1 LAST COMMENT_BODY TRUE
J 0
(-1750 3000);
DISPLAY 0.978723 (-1750 3000);
PAINT ORANGE (-1750 3000);
DISPLAY INVISIBLE (-1750 3000);
FORCEPROP 2 LAST CDS_LIB mstr_symbols
J 0
(-1775 2900);
PAINT MONO (-1775 2900);
DISPLAY INVISIBLE (-1775 2900);
FORCEADD INTEL_CORP_BPAGE..1
(-200 25);
FORCEPROP 1 LAST CDS_CON_LAST_MODIFIED Tue Dec 01 11:52:18 2015
J 0
(-1625 350);
PAINT ORANGE (-1625 350);
DISPLAY INVISIBLE (-1625 350);
FORCEPROP 2 LAST CUSTOM_TXT_CDS <XR_PAGE_TITLE>
J 0
(-8090 5275);
DISPLAY 0.638298 (-8090 5275);
PAINT PINK (-8090 5275);
DISPLAY INVISIBLE (-8090 5275);
FORCEPROP 2 LAST CUSTOM_TXT_CDS <CON_LAST_MODIFIED>
J 0
(-2125 375);
PAINT ORANGE (-2125 375);
FORCEPROP 2 LAST CUSTOM_TXT_CDS <CURRENT_DESIGN_SHEET> OF <TOTAL_DESIGN_SHEETS>
J 0
(-700 50);
PAINT ORANGE (-700 50);
FORCEPROP 1 LAST SCH_TITLE CPLD (2 OF 3)
J 0
(-8150 75);
DISPLAY 1.212766 (-8150 75);
PAINT ORANGE (-8150 75);
FORCEPROP 1 LAST SCH_ADDRESS1 2200 Mission College Blvd.
J 0
(-4175 150);
DISPLAY 0.617021 (-4175 150);
PAINT GREEN (-4175 150);
FORCEPROP 1 LAST SCH_ADDRESS2 P.O. BOX 58119
J 0
(-4175 100);
DISPLAY 0.617021 (-4175 100);
PAINT GREEN (-4175 100);
FORCEPROP 1 LAST SCH_ADDRESS3 Santa Clara, CA 95052-8119
J 0
(-4175 50);
DISPLAY 0.617021 (-4175 50);
PAINT GREEN (-4175 50);
FORCEPROP 1 LAST SCH_NUMBER H4694802
J 0
(-1500 175);
DISPLAY 1.212766 (-1500 175);
PAINT YELLOW (-1500 175);
FORCEPROP 1 LAST SCH_DEPT BESD
J 1
(-4650 125);
DISPLAY 1.212766 (-4650 125);
PAINT YELLOW (-4650 125);
FORCEPROP 1 LAST SCH_REV 2.420
J 0
(-450 175);
DISPLAY 1.212766 (-450 175);
PAINT YELLOW (-450 175);
FORCEPROP 2 LAST CDS_LIB mstr_symbols
J 0
(-200 25);
PAINT ORANGE (-200 25);
DISPLAY INVISIBLE (-200 25);
FORCEPROP 2 LAST PAGE_BORDER TRUE
J 0
(-8090 5275);
DISPLAY 0.638298 (-8090 5275);
PAINT PINK (-8090 5275);
DISPLAY INVISIBLE (-8090 5275);
FORCEPROP 1 LAST COMMENT_BODY TRUE
J 0
(-188 37);
DISPLAY 0.468085 (-188 37);
PAINT GREEN (-188 37);
DISPLAY INVISIBLE (-188 37);
FORCEPROP 2 LAST CDS_XR_PAGE_TITLE CR-191 : @BASEBOARD_FAB2_LIB.BASEBOARD_FAB2(SCH_1):PAGE191
J 0
(-8090 5275);
DISPLAY 0.638298 (-8090 5275);
PAINT PINK (-8090 5275);
DISPLAY INVISIBLE (-8090 5275);
WIRE 16 -1 (-1375 3650)(-1375 3700);
WIRE 16 -1 (-7225 2850)(-7225 2775);
WIRE 16 -1 (-3875 4325)(-3300 4325);
FORCEPROP 2 LAST SIG_NAME FM_ADR_SMI_GPIO_R_N
J 0
(-3710 4335);
DISPLAY 0.617021 (-3710 4335);
PAINT ORANGE (-3710 4335);
FORCEPROP 2 LASTPROP $XRERR UNIQUE?
J 0
(-3950 4335);
DISPLAY 0.638298 (-3950 4335);
PAINT MONO (-3950 4335);
DISPLAY INVISIBLE (-3950 4335);
WIRE 16 -1 (-5075 2475)(-7225 2475);
FORCEPROP 2 LAST SIG_NAME PU_FAB2_MARKER_CPLD
J 0
(-5941 2493);
DISPLAY 0.617021 (-5941 2493);
PAINT ORANGE (-5941 2493);
FORCEPROP 2 LASTPROP $XRERR UNIQUE?
J 0
(-6181 2493);
DISPLAY 0.638298 (-6181 2493);
PAINT MONO (-6181 2493);
DISPLAY INVISIBLE (-6181 2493);
WIRE 16 -1 (-7225 2575)(-7225 2475);
WIRE 16 -1 (-5075 2125)(-6375 2125);
FORCEPROP 2 LAST SIG_NAME PWRGD_P3V3_STBY
J 0
(-6325 2143);
DISPLAY 0.617021 (-6325 2143);
PAINT ORANGE (-6325 2143);
WIRE 16 -1 (-5075 3225)(-6375 3225);
FORCEPROP 2 LAST SIG_NAME FM_CPU1_THERMTRIP_LVT3_N
J 0
(-6325 3243);
DISPLAY 0.617021 (-6325 3243);
PAINT ORANGE (-6325 3243);
WIRE 16 -1 (-6375 4025)(-5075 4025);
FORCEPROP 0 LAST SIG_NAME FM_CPLD_ADR_TRIGGER_N
J 0
(-6325 4035);
DISPLAY 0.617021 (-6325 4035);
PAINT ORANGE (-6325 4035);
WIRE 16 -1 (-5075 3975)(-6375 3975);
FORCEPROP 2 LAST SIG_NAME PWRGD_PCH_PWROK
J 0
(-6325 3993);
DISPLAY 0.617021 (-6325 3993);
PAINT ORANGE (-6325 3993);
WIRE 16 -1 (-5075 3525)(-6375 3525);
FORCEPROP 2 LAST SIG_NAME RST_BMC_SYSRST_BTN_OUT_B_N
J 0
(-6325 3543);
DISPLAY 0.617021 (-6325 3543);
PAINT ORANGE (-6325 3543);
WIRE 16 -1 (-5075 3675)(-6375 3675);
FORCEPROP 2 LAST SIG_NAME PWRGD_CPUPWRGD
J 0
(-6325 3693);
DISPLAY 0.617021 (-6325 3693);
PAINT ORANGE (-6325 3693);
WIRE 16 -1 (-5075 1375)(-6375 1375);
FORCEPROP 2 LAST SIG_NAME FM_PVPP_CPU1_EN
J 0
(-6325 1393);
DISPLAY 0.617021 (-6325 1393);
PAINT ORANGE (-6325 1393);
WIRE 16 -1 (-5075 1425)(-6375 1425);
FORCEPROP 2 LAST SIG_NAME FM_CPU0_THERMTRIP_LVT3_N
J 0
(-6325 1443);
DISPLAY 0.617021 (-6325 1443);
PAINT ORANGE (-6325 1443);
WIRE 16 -1 (-5075 2225)(-6375 2225);
FORCEPROP 2 LAST SIG_NAME FM_PVDDQ_DEF_EN
J 0
(-6325 2243);
DISPLAY 0.617021 (-6325 2243);
PAINT ORANGE (-6325 2243);
WIRE 16 -1 (-5075 2975)(-6375 2975);
FORCEPROP 2 LAST SIG_NAME FM_PVDDQ_KLM_EN
J 0
(-6325 2993);
DISPLAY 0.617021 (-6325 2993);
PAINT ORANGE (-6325 2993);
WIRE 16 -1 (-5075 2275)(-6375 2275);
FORCEPROP 2 LAST SIG_NAME FM_PVDDQ_ABC_EN
J 0
(-6325 2293);
DISPLAY 0.617021 (-6325 2293);
PAINT ORANGE (-6325 2293);
WIRE 16 -1 (-5075 3025)(-6375 3025);
FORCEPROP 2 LAST SIG_NAME FM_FAST_PROCHOT_THROTTLE_IN_N
J 0
(-6325 3043);
DISPLAY 0.617021 (-6325 3043);
PAINT ORANGE (-6325 3043);
WIRE 16 -1 (-5075 2875)(-6375 2875);
FORCEPROP 2 LAST SIG_NAME FM_FAST_PROCHOT_THROTTLE_DLY_N
J 0
(-6325 2893);
DISPLAY 0.617021 (-6325 2893);
PAINT ORANGE (-6325 2893);
WIRE 16 -1 (-5075 3175)(-6375 3175);
FORCEPROP 2 LAST SIG_NAME FM_WBG_PRSNT_N
J 0
(-6325 3193);
DISPLAY 0.617021 (-6325 3193);
PAINT ORANGE (-6325 3193);
WIRE 16 -1 (-5075 3275)(-6375 3275);
FORCEPROP 2 LAST SIG_NAME FM_UV_ADR_TRIGGER_N
J 0
(-6325 3293);
DISPLAY 0.617021 (-6325 3293);
PAINT ORANGE (-6325 3293);
WIRE 16 -1 (-5075 3125)(-6375 3125);
FORCEPROP 2 LAST SIG_NAME FM_UV_ADR_TRIGGER_EN
J 0
(-6325 3143);
DISPLAY 0.617021 (-6325 3143);
PAINT ORANGE (-6325 3143);
WIRE 16 -1 (-5075 3625)(-6375 3625);
FORCEPROP 2 LAST SIG_NAME FM_CPU0_THERMTRIP_LATCH_LVT3_N
J 0
(-6325 3643);
DISPLAY 0.617021 (-6325 3643);
PAINT ORANGE (-6325 3643);
WIRE 16 -1 (-5075 1875)(-6375 1875);
FORCEPROP 2 LAST SIG_NAME FM_MEM_THERM_EVENT_PCH_N
J 0
(-6325 1893);
DISPLAY 0.617021 (-6325 1893);
PAINT ORANGE (-6325 1893);
WIRE 16 -1 (-5075 2925)(-6375 2925);
FORCEPROP 2 LAST SIG_NAME FM_PVDDQ_GHJ_EN
J 0
(-6325 2943);
DISPLAY 0.617021 (-6325 2943);
PAINT ORANGE (-6325 2943);
WIRE 16 -1 (-5075 2025)(-6375 2025);
FORCEPROP 2 LAST SIG_NAME PWRGD_PVCCIO_CPU1
J 0
(-6325 2043);
DISPLAY 0.617021 (-6325 2043);
PAINT ORANGE (-6325 2043);
WIRE 16 -1 (-5075 1275)(-6375 1275);
FORCEPROP 2 LAST SIG_NAME FM_PVCCIN_PVCCSA_CPU1_EN_LVC1
J 0
(-6325 1293);
DISPLAY 0.617021 (-6325 1293);
PAINT ORANGE (-6325 1293);
WIRE 16 -1 (-5075 4075)(-6375 4075);
FORCEPROP 2 LAST SIG_NAME PWRGD_P1V8MCP_CPU1
J 0
(-6325 4093);
DISPLAY 0.617021 (-6325 4093);
PAINT ORANGE (-6325 4093);
WIRE 16 -1 (-5075 3925)(-6375 3925);
FORCEPROP 2 LAST SIG_NAME PWRGD_P1V8MCP_CPU0
J 0
(-6325 3943);
DISPLAY 0.617021 (-6325 3943);
PAINT ORANGE (-6325 3943);
WIRE 16 -1 (-5075 3775)(-6375 3775);
FORCEPROP 2 LAST SIG_NAME FM_P1V8MCP_CPU0_EN
J 0
(-6325 3793);
DISPLAY 0.617021 (-6325 3793);
PAINT ORANGE (-6325 3793);
WIRE 16 -1 (-5075 3425)(-6375 3425);
FORCEPROP 2 LAST SIG_NAME FM_P1V8MCP_CPU1_EN
J 0
(-6325 3443);
DISPLAY 0.617021 (-6325 3443);
PAINT ORANGE (-6325 3443);
WIRE 16 -1 (-5075 3725)(-6375 3725);
FORCEPROP 2 LAST SIG_NAME FM_CPU0_MCP_CLK_EN_N
J 0
(-6325 3735);
DISPLAY 0.617021 (-6325 3735);
PAINT ORANGE (-6325 3735);
WIRE 16 -1 (-5075 3475)(-6375 3475);
FORCEPROP 2 LAST SIG_NAME FM_CPU1_MCP_CLK_EN_N
J 0
(-6325 3485);
DISPLAY 0.617021 (-6325 3485);
PAINT ORANGE (-6325 3485);
WIRE 16 -1 (-5075 1225)(-6375 1225);
FORCEPROP 2 LAST SIG_NAME FM_CPU1_VRM_OSC_EN
J 0
(-6325 1243);
DISPLAY 0.617021 (-6325 1243);
PAINT ORANGE (-6325 1243);
WIRE 16 -1 (-5075 3375)(-6375 3375);
FORCEPROP 2 LAST SIG_NAME FM_CPU1_FIVR_FAULT_LVT3
J 0
(-6325 3393);
DISPLAY 0.617021 (-6325 3393);
PAINT ORANGE (-6325 3393);
WIRE 16 -1 (-5075 1175)(-6375 1175);
FORCEPROP 2 LAST SIG_NAME FM_PVPP_CPU0_EN
J 0
(-6325 1193);
DISPLAY 0.617021 (-6325 1193);
PAINT ORANGE (-6325 1193);
WIRE 16 -1 (-5075 1125)(-6375 1125);
FORCEPROP 2 LAST SIG_NAME FM_P12V_MAIN_SW_EN
J 0
(-6325 1143);
DISPLAY 0.617021 (-6325 1143);
PAINT ORANGE (-6325 1143);
WIRE 16 -1 (-5075 1525)(-6375 1525);
FORCEPROP 2 LAST SIG_NAME FM_CPU1_PROC_ID1
J 0
(-6325 1543);
DISPLAY 0.617021 (-6325 1543);
PAINT ORANGE (-6325 1543);
WIRE 16 -1 (-5075 1725)(-6375 1725);
FORCEPROP 2 LAST SIG_NAME FM_CPU0_FIVR_FAULT_LVT3
J 0
(-6325 1743);
DISPLAY 0.617021 (-6325 1743);
PAINT ORANGE (-6325 1743);
WIRE 16 -1 (-5075 1675)(-6375 1675);
FORCEPROP 2 LAST SIG_NAME RST_PLTRST_BUF_N
J 0
(-6325 1693);
DISPLAY 0.617021 (-6325 1693);
PAINT ORANGE (-6325 1693);
WIRE 16 -1 (-5075 1775)(-6375 1775);
FORCEPROP 2 LAST SIG_NAME FM_THERMTRIP_DLY
J 0
(-6325 1793);
DISPLAY 0.617021 (-6325 1793);
PAINT ORANGE (-6325 1793);
WIRE 16 -1 (-5075 1925)(-6375 1925);
FORCEPROP 2 LAST SIG_NAME FM_MEM_THERM_EVENT_LVT3_N
J 0
(-6325 1943);
DISPLAY 0.617021 (-6325 1943);
PAINT ORANGE (-6325 1943);
WIRE 16 -1 (-5075 1475)(-6375 1475);
FORCEPROP 2 LAST SIG_NAME FM_CPU1_PROC_ID0
J 0
(-6325 1493);
DISPLAY 0.617021 (-6325 1493);
PAINT ORANGE (-6325 1493);
WIRE 16 -1 (-5075 1625)(-5975 1625);
FORCEPROP 2 LAST SIG_NAME TP_CPLD1_PR12D
J 0
(-5941 1643);
DISPLAY 0.617021 (-5941 1643);
PAINT ORANGE (-5941 1643);
FORCEPROP 2 LASTPROP $XRERR UNIQUE?
J 0
(-6215 1625);
DISPLAY 0.638298 (-6215 1625);
PAINT MONO (-6215 1625);
DISPLAY INVISIBLE (-6215 1625);
WIRE 16 -1 (-5075 1975)(-6025 1975);
FORCEPROP 2 LAST SIG_NAME TP_CPLD1_PR11B
J 0
(-5975 1993);
DISPLAY 0.617021 (-5975 1993);
PAINT ORANGE (-5975 1993);
FORCEPROP 2 LASTPROP $XRERR UNIQUE?
J 0
(-6265 1975);
DISPLAY 0.638298 (-6265 1975);
PAINT MONO (-6265 1975);
DISPLAY INVISIBLE (-6265 1975);
WIRE 16 -1 (-5075 2175)(-6025 2175);
FORCEPROP 2 LAST SIG_NAME TP_CPLD1_PR10C
J 0
(-5975 2193);
DISPLAY 0.617021 (-5975 2193);
PAINT ORANGE (-5975 2193);
FORCEPROP 2 LASTPROP $XRERR UNIQUE?
J 0
(-6265 2175);
DISPLAY 0.638298 (-6265 2175);
PAINT MONO (-6265 2175);
DISPLAY INVISIBLE (-6265 2175);
WIRE 16 -1 (-5075 2375)(-6025 2375);
FORCEPROP 2 LAST SIG_NAME TP_CPLD1_PR9D
J 0
(-5941 2393);
DISPLAY 0.617021 (-5941 2393);
PAINT ORANGE (-5941 2393);
FORCEPROP 2 LASTPROP $XRERR UNIQUE?
J 0
(-6265 2375);
DISPLAY 0.638298 (-6265 2375);
PAINT MONO (-6265 2375);
DISPLAY INVISIBLE (-6265 2375);
WIRE 16 -1 (-5075 2425)(-6025 2425);
FORCEPROP 2 LAST SIG_NAME TP_CPLD1_PR9C
J 0
(-5941 2443);
DISPLAY 0.617021 (-5941 2443);
PAINT ORANGE (-5941 2443);
FORCEPROP 2 LASTPROP $XRERR UNIQUE?
J 0
(-6265 2425);
DISPLAY 0.638298 (-6265 2425);
PAINT MONO (-6265 2425);
DISPLAY INVISIBLE (-6265 2425);
WIRE 16 -1 (-5075 2525)(-6025 2525);
FORCEPROP 2 LAST SIG_NAME TP_CPLD1_PR9A
J 0
(-5941 2543);
DISPLAY 0.617021 (-5941 2543);
PAINT ORANGE (-5941 2543);
FORCEPROP 2 LASTPROP $XRERR UNIQUE?
J 0
(-6265 2525);
DISPLAY 0.638298 (-6265 2525);
PAINT MONO (-6265 2525);
DISPLAY INVISIBLE (-6265 2525);
WIRE 16 -1 (-5075 2625)(-6025 2625);
FORCEPROP 2 LAST SIG_NAME TP_CPLD1_PR7D
J 0
(-5941 2643);
DISPLAY 0.617021 (-5941 2643);
PAINT ORANGE (-5941 2643);
FORCEPROP 2 LASTPROP $XRERR UNIQUE?
J 0
(-6265 2625);
DISPLAY 0.638298 (-6265 2625);
PAINT MONO (-6265 2625);
DISPLAY INVISIBLE (-6265 2625);
WIRE 16 -1 (-5075 2675)(-6025 2675);
FORCEPROP 2 LAST SIG_NAME TP_CPLD1_PR7C
J 0
(-5941 2693);
DISPLAY 0.617021 (-5941 2693);
PAINT ORANGE (-5941 2693);
FORCEPROP 2 LASTPROP $XRERR UNIQUE?
J 0
(-6265 2675);
DISPLAY 0.638298 (-6265 2675);
PAINT MONO (-6265 2675);
DISPLAY INVISIBLE (-6265 2675);
WIRE 16 -1 (-5075 2725)(-6025 2725);
FORCEPROP 2 LAST SIG_NAME TP_CPLD1_PR7B_PCLKC1_0
J 0
(-5941 2743);
DISPLAY 0.617021 (-5941 2743);
PAINT ORANGE (-5941 2743);
FORCEPROP 2 LASTPROP $XRERR UNIQUE?
J 0
(-6265 2725);
DISPLAY 0.638298 (-6265 2725);
PAINT MONO (-6265 2725);
DISPLAY INVISIBLE (-6265 2725);
WIRE 16 -1 (-5075 2775)(-6025 2775);
FORCEPROP 2 LAST SIG_NAME TP_CPLD1_PR7A_PCLKT1_0
J 0
(-5941 2793);
DISPLAY 0.617021 (-5941 2793);
PAINT ORANGE (-5941 2793);
FORCEPROP 2 LASTPROP $XRERR UNIQUE?
J 0
(-6265 2775);
DISPLAY 0.638298 (-6265 2775);
PAINT MONO (-6265 2775);
DISPLAY INVISIBLE (-6265 2775);
WIRE 16 -1 (-5075 4275)(-6375 4275);
FORCEPROP 2 LAST SIG_NAME RST_PLTRST_N
J 0
(-6325 4293);
DISPLAY 0.617021 (-6325 4293);
PAINT ORANGE (-6325 4293);
WIRE 16 -1 (-5075 4325)(-6375 4325);
FORCEPROP 2 LAST SIG_NAME PWRGD_SYS_PWROK
J 0
(-6325 4343);
DISPLAY 0.617021 (-6325 4343);
PAINT ORANGE (-6325 4343);
WIRE 16 -1 (-5075 4175)(-6375 4175);
FORCEPROP 2 LAST SIG_NAME FM_ADR_COMPLETE_DLY
J 0
(-6325 4193);
DISPLAY 0.617021 (-6325 4193);
PAINT ORANGE (-6325 4193);
WIRE 16 -1 (-5075 4225)(-6375 4225);
FORCEPROP 2 LAST SIG_NAME FM_DB1200_PWRGD
J 0
(-6325 4243);
DISPLAY 0.617021 (-6325 4243);
PAINT ORANGE (-6325 4243);
WIRE 16 -1 (-3875 2025)(-3175 2025);
FORCEPROP 0 LAST SIG_NAME TP_CPLD1_PT20D_PROGRAMN
J 0
(-3700 2035);
DISPLAY 0.617021 (-3700 2035);
PAINT ORANGE (-3700 2035);
FORCEPROP 2 LASTPROP $XRERR UNIQUE?
J 0
(-3003 2035);
DISPLAY 0.638298 (-3003 2035);
PAINT MONO (-3003 2035);
DISPLAY INVISIBLE (-3003 2035);
WIRE 16 -1 (-3875 1125)(-3200 1125);
FORCEPROP 2 LAST SIG_NAME TP_CPLD1_PT24D_DONE
J 0
(-3700 1135);
DISPLAY 0.617021 (-3700 1135);
PAINT ORANGE (-3700 1135);
FORCEPROP 2 LASTPROP $XRERR UNIQUE?
J 0
(-3119 1135);
DISPLAY 0.638298 (-3119 1135);
PAINT MONO (-3119 1135);
DISPLAY INVISIBLE (-3119 1135);
WIRE 16 -1 (-3875 1175)(-3200 1175);
FORCEPROP 2 LAST SIG_NAME TP_CPLD1_PT24C_INITN
J 0
(-3700 1185);
DISPLAY 0.617021 (-3700 1185);
PAINT ORANGE (-3700 1185);
FORCEPROP 2 LASTPROP $XRERR UNIQUE?
J 0
(-3090 1185);
DISPLAY 0.638298 (-3090 1185);
PAINT MONO (-3090 1185);
DISPLAY INVISIBLE (-3090 1185);
WIRE 16 -1 (-3875 1225)(-3200 1225);
FORCEPROP 2 LAST SIG_NAME TP_CPLD1_PT24B
J 0
(-3690 1235);
DISPLAY 0.617021 (-3690 1235);
PAINT ORANGE (-3690 1235);
FORCEPROP 2 LASTPROP $XRERR UNIQUE?
J 0
(-3170 1225);
DISPLAY 0.638298 (-3170 1225);
PAINT MONO (-3170 1225);
DISPLAY INVISIBLE (-3170 1225);
WIRE 16 -1 (-3875 1525)(-3200 1525);
FORCEPROP 0 LAST SIG_NAME TP_CPLD1_PT22D
J 0
(-3700 1535);
DISPLAY 0.617021 (-3700 1535);
PAINT ORANGE (-3700 1535);
FORCEPROP 2 LASTPROP $XRERR UNIQUE?
J 0
(-3170 1525);
DISPLAY 0.638298 (-3170 1525);
PAINT MONO (-3170 1525);
DISPLAY INVISIBLE (-3170 1525);
WIRE 16 -1 (-3875 1575)(-3200 1575);
FORCEPROP 2 LAST SIG_NAME TP_CPLD1_PT22C
J 0
(-3700 1593);
DISPLAY 0.617021 (-3700 1593);
PAINT ORANGE (-3700 1593);
FORCEPROP 2 LASTPROP $XRERR UNIQUE?
J 0
(-3170 1575);
DISPLAY 0.638298 (-3170 1575);
PAINT MONO (-3170 1575);
DISPLAY INVISIBLE (-3170 1575);
WIRE 16 -1 (-3875 1275)(-2500 1275);
FORCEPROP 2 LAST SIG_NAME FM_SINT_PRSNT_N
J 0
(-3085 1285);
DISPLAY 0.617021 (-3085 1285);
PAINT ORANGE (-3085 1285);
WIRE 16 -1 (-3875 1375)(-2500 1375);
FORCEPROP 2 LAST SIG_NAME FM_PCH_PWRBTN_N
J 0
(-3085 1393);
DISPLAY 0.617021 (-3085 1393);
PAINT ORANGE (-3085 1393);
WIRE 16 -1 (-3875 1425)(-2500 1425);
FORCEPROP 0 LAST SIG_NAME FM_SLPS4_N
J 0
(-3085 1435);
DISPLAY 0.617021 (-3085 1435);
PAINT ORANGE (-3085 1435);
WIRE 16 -1 (-3875 1925)(-2500 1925);
FORCEPROP 0 LAST SIG_NAME FM_CPU0_OR_CPU1_MCP_PRES
J 0
(-3075 1935);
DISPLAY 0.617021 (-3075 1935);
PAINT ORANGE (-3075 1935);
WIRE 16 -1 (-3875 1875)(-2500 1875);
FORCEPROP 0 LAST SIG_NAME FM_CPU0_CD_PRES
J 0
(-3075 1885);
DISPLAY 0.617021 (-3075 1885);
PAINT ORANGE (-3075 1885);
WIRE 16 -1 (-3875 1825)(-2500 1825);
FORCEPROP 0 LAST SIG_NAME FM_CPU1_CD_PRES
J 0
(-3075 1835);
DISPLAY 0.617021 (-3075 1835);
PAINT ORANGE (-3075 1835);
WIRE 16 -1 (-3875 1775)(-2500 1775);
FORCEPROP 0 LAST SIG_NAME FM_CPU0_AND_CPU1_MCP_PRES
J 0
(-3075 1785);
DISPLAY 0.617021 (-3075 1785);
PAINT ORANGE (-3075 1785);
WIRE 16 -1 (-3875 1675)(-2500 1675);
FORCEPROP 0 LAST SIG_NAME PWRGD_DSW_PWROK
J 0
(-3085 1685);
DISPLAY 0.617021 (-3085 1685);
PAINT ORANGE (-3085 1685);
WIRE 16 -1 (-3875 1625)(-2500 1625);
FORCEPROP 2 LAST SIG_NAME PU_THERMTRIP_FORCE_N
J 0
(-3085 1643);
DISPLAY 0.617021 (-3085 1643);
PAINT ORANGE (-3085 1643);
WIRE 16 -1 (-3875 2275)(-3175 2275);
FORCEPROP 0 LAST SIG_NAME TP_CPLD1_PT19D
J 0
(-3700 2285);
DISPLAY 0.617021 (-3700 2285);
PAINT ORANGE (-3700 2285);
FORCEPROP 2 LASTPROP $XRERR UNIQUE?
J 0
(-3145 2275);
DISPLAY 0.638298 (-3145 2275);
PAINT MONO (-3145 2275);
DISPLAY INVISIBLE (-3145 2275);
WIRE 16 -1 (-3875 2125)(-3175 2125);
FORCEPROP 0 LAST SIG_NAME TP_CPLD1_PT20B
J 0
(-3700 2135);
DISPLAY 0.617021 (-3700 2135);
PAINT ORANGE (-3700 2135);
FORCEPROP 2 LASTPROP $XRERR UNIQUE?
J 0
(-3145 2125);
DISPLAY 0.638298 (-3145 2125);
PAINT MONO (-3145 2125);
DISPLAY INVISIBLE (-3145 2125);
WIRE 16 -1 (-3875 2175)(-3175 2175);
FORCEPROP 0 LAST SIG_NAME TP_CPLD1_PT20A
J 0
(-3700 2185);
DISPLAY 0.617021 (-3700 2185);
PAINT ORANGE (-3700 2185);
FORCEPROP 2 LASTPROP $XRERR UNIQUE?
J 0
(-3145 2175);
DISPLAY 0.638298 (-3145 2175);
PAINT MONO (-3145 2175);
DISPLAY INVISIBLE (-3145 2175);
WIRE 16 -1 (-3875 2875)(-3175 2875);
FORCEPROP 0 LAST SIG_NAME TP_CPLD1_PT17C
J 0
(-3685 2885);
DISPLAY 0.617021 (-3685 2885);
PAINT ORANGE (-3685 2885);
FORCEPROP 2 LASTPROP $XRERR UNIQUE?
J 0
(-3145 2875);
DISPLAY 0.638298 (-3145 2875);
PAINT MONO (-3145 2875);
DISPLAY INVISIBLE (-3145 2875);
WIRE 16 -1 (-3875 2925)(-3175 2925);
FORCEPROP 0 LAST SIG_NAME TP_CPLD1_PT17B_PCLKC0_1
J 0
(-3690 2935);
DISPLAY 0.617021 (-3690 2935);
PAINT ORANGE (-3690 2935);
FORCEPROP 2 LASTPROP $XRERR UNIQUE?
J 0
(-2993 2935);
DISPLAY 0.638298 (-2993 2935);
PAINT MONO (-2993 2935);
DISPLAY INVISIBLE (-2993 2935);
WIRE 16 -1 (-3875 3175)(-3175 3175);
FORCEPROP 0 LAST SIG_NAME TP_CPLD1_PT16B
J 0
(-3690 3185);
DISPLAY 0.617021 (-3690 3185);
PAINT ORANGE (-3690 3185);
FORCEPROP 2 LASTPROP $XRERR UNIQUE?
J 0
(-3145 3175);
DISPLAY 0.638298 (-3145 3175);
PAINT MONO (-3145 3175);
DISPLAY INVISIBLE (-3145 3175);
WIRE 16 -1 (-3875 3475)(-3175 3475);
FORCEPROP 0 LAST SIG_NAME TP_CPLD1_PT13A
J 0
(-3690 3485);
DISPLAY 0.617021 (-3690 3485);
PAINT ORANGE (-3690 3485);
FORCEPROP 2 LASTPROP $XRERR UNIQUE?
J 0
(-3145 3475);
DISPLAY 0.638298 (-3145 3475);
PAINT MONO (-3145 3475);
DISPLAY INVISIBLE (-3145 3475);
WIRE 16 -1 (-3875 3925)(-3150 3925);
FORCEPROP 0 LAST SIG_NAME TP_CPLD1_PT11B
J 0
(-3690 3935);
DISPLAY 0.617021 (-3690 3935);
PAINT ORANGE (-3690 3935);
FORCEPROP 2 LASTPROP $XRERR UNIQUE?
J 0
(-3120 3925);
DISPLAY 0.638298 (-3120 3925);
PAINT MONO (-3120 3925);
DISPLAY INVISIBLE (-3120 3925);
WIRE 16 -1 (-3875 3975)(-3150 3975);
FORCEPROP 0 LAST SIG_NAME TP_CPLD1_PT11A
J 0
(-3690 3985);
DISPLAY 0.617021 (-3690 3985);
PAINT ORANGE (-3690 3985);
FORCEPROP 2 LASTPROP $XRERR UNIQUE?
J 0
(-3120 3975);
DISPLAY 0.638298 (-3120 3975);
PAINT MONO (-3120 3975);
DISPLAY INVISIBLE (-3120 3975);
WIRE 16 -1 (-3875 2075)(-2500 2075);
FORCEPROP 2 LAST SIG_NAME FM_JTAG_PLD_EN_DEBUG
J 0
(-3085 2093);
DISPLAY 0.617021 (-3085 2093);
PAINT ORANGE (-3085 2093);
WIRE 16 -1 (-3875 2525)(-2500 2525);
FORCEPROP 0 LAST SIG_NAME SMB_SENSOR_STBY_LVC3_SDA
J 0
(-3085 2535);
DISPLAY 0.617021 (-3085 2535);
PAINT ORANGE (-3085 2535);
WIRE 16 -1 (-3875 2825)(-2500 2825);
FORCEPROP 0 LAST SIG_NAME FM_SLP_SUS_N
J 0
(-3085 2835);
DISPLAY 0.617021 (-3085 2835);
PAINT ORANGE (-3085 2835);
WIRE 16 -1 (-3875 2975)(-2500 2975);
FORCEPROP 0 LAST SIG_NAME FM_ADR_COMPLETE
J 0
(-3060 2985);
DISPLAY 0.617021 (-3060 2985);
PAINT ORANGE (-3060 2985);
WIRE 16 -1 (-3875 3425)(-2500 3425);
FORCEPROP 0 LAST SIG_NAME FM_BMC_ONCTL_N
J 0
(-3085 3435);
DISPLAY 0.617021 (-3085 3435);
PAINT ORANGE (-3085 3435);
WIRE 16 -1 (-3875 3725)(-2500 3725);
FORCEPROP 0 LAST SIG_NAME RST_PCIE_CPU_DEV0_N
J 0
(-3085 3735);
DISPLAY 0.617021 (-3085 3735);
PAINT ORANGE (-3085 3735);
WIRE 16 -1 (-3875 3825)(-2500 3825);
FORCEPROP 0 LAST SIG_NAME PWRGD_PVTT_CPU0
J 0
(-3085 3835);
DISPLAY 0.617021 (-3085 3835);
PAINT ORANGE (-3085 3835);
WIRE 16 -1 (-3875 3875)(-2500 3875);
FORCEPROP 0 LAST SIG_NAME FM_PCH_PRSNT_N
J 0
(-3085 3885);
DISPLAY 0.617021 (-3085 3885);
PAINT ORANGE (-3085 3885);
WIRE 16 -1 (-3875 2625)(-2500 2625);
FORCEPROP 0 LAST SIG_NAME RST_PCIE_MIDPLANE_N
J 0
(-3085 2635);
DISPLAY 0.617021 (-3085 2635);
PAINT ORANGE (-3085 2635);
WIRE 16 -1 (-3875 2425)(-2500 2425);
FORCEPROP 0 LAST SIG_NAME PU_RST_PERST_BIT1
J 0
(-3085 2435);
DISPLAY 0.617021 (-3085 2435);
PAINT ORANGE (-3085 2435);
WIRE 16 -1 (-3875 3675)(-2500 3675);
FORCEPROP 0 LAST SIG_NAME PWRGD_P1V26_BMC_STBY
J 0
(-3085 3685);
DISPLAY 0.617021 (-3085 3685);
PAINT ORANGE (-3085 3685);
WIRE 16 -1 (-3875 4075)(-2500 4075);
FORCEPROP 0 LAST SIG_NAME FM_CPU1_THERMTRIP_LATCH_LVT3_N
J 0
(-3235 4085);
DISPLAY 0.617021 (-3235 4085);
PAINT ORANGE (-3235 4085);
WIRE 16 -1 (-3875 2375)(-2500 2375);
FORCEPROP 0 LAST SIG_NAME FM_PVCCIN_PVCCSA_CPU0_EN_LVC1
J 0
(-3090 2385);
DISPLAY 0.617021 (-3090 2385);
PAINT ORANGE (-3090 2385);
WIRE 16 -1 (-3875 3625)(-2500 3625);
FORCEPROP 0 LAST SIG_NAME JTAG_PLD_TDO
J 0
(-3085 3635);
DISPLAY 0.617021 (-3085 3635);
PAINT ORANGE (-3085 3635);
WIRE 16 -1 (-3875 3575)(-2500 3575);
FORCEPROP 0 LAST SIG_NAME JTAG_PLD_TDI
J 0
(-3085 3585);
DISPLAY 0.617021 (-3085 3585);
PAINT ORANGE (-3085 3585);
WIRE 16 -1 (-3875 3375)(-2500 3375);
FORCEPROP 0 LAST SIG_NAME FM_CPU1_FIVR_FAULT_LVT3_N
J 0
(-3085 3385);
DISPLAY 0.617021 (-3085 3385);
PAINT ORANGE (-3085 3385);
WIRE 16 -1 (-3875 3225)(-2500 3225);
FORCEPROP 0 LAST SIG_NAME FM_PLD_DEBUG_MODE_N
J 0
(-3085 3235);
DISPLAY 0.617021 (-3085 3235);
PAINT ORANGE (-3085 3235);
WIRE 16 -1 (-3875 3125)(-2500 3125);
FORCEPROP 0 LAST SIG_NAME JTAG_PLD_TCK
J 0
(-3085 3135);
DISPLAY 0.617021 (-3085 3135);
PAINT ORANGE (-3085 3135);
WIRE 16 -1 (-3875 3075)(-2500 3075);
FORCEPROP 0 LAST SIG_NAME JTAG_PLD_TMS
J 0
(-3085 3085);
DISPLAY 0.617021 (-3085 3085);
PAINT ORANGE (-3085 3085);
WIRE 16 -1 (-3875 2575)(-2500 2575);
FORCEPROP 0 LAST SIG_NAME SMB_SENSOR_STBY_LVC3_SCL
J 0
(-3085 2585);
DISPLAY 0.617021 (-3085 2585);
PAINT ORANGE (-3085 2585);
WIRE 16 -1 (-3875 2325)(-2500 2325);
FORCEPROP 0 LAST SIG_NAME FM_PS_EN
J 0
(-3085 2335);
DISPLAY 0.617021 (-3085 2335);
PAINT ORANGE (-3085 2335);
WIRE 16 -1 (-3875 2675)(-1525 2675);
FORCEPROP 0 LAST SIG_NAME SGPIO_BMC_DIN_R
J 0
(-3085 2675);
DISPLAY 0.617021 (-3085 2675);
PAINT ORANGE (-3085 2675);
FORCEPROP 2 LASTPROP $XRERR UNIQUE?
J 0
(-3325 2675);
DISPLAY 0.638298 (-3325 2675);
PAINT MONO (-3325 2675);
DISPLAY INVISIBLE (-3325 2675);
WIRE 16 -1 (-1325 2675)(-900 2675);
WIRE 16 -1 (-1375 3450)(-1375 3325);
WIRE 16 -1 (-1375 3325)(-900 3325);
FORCEPROP 0 LAST SIG_NAME FM_FORCE_ADR_N
J 2
(-910 3335);
DISPLAY 0.617021 (-910 3335);
PAINT ORANGE (-910 3335);
WIRE 16 -1 (-3875 3325)(-1375 3325);
WIRE 16 -1 (-3875 4225)(-2500 4225);
FORCEPROP 0 LAST SIG_NAME FM_CTNR_PS_ON
J 0
(-3085 4235);
DISPLAY 0.617021 (-3085 4235);
PAINT ORANGE (-3085 4235);
WIRE 16 -1 (-3875 4125)(-2500 4125);
FORCEPROP 0 LAST SIG_NAME FM_P3V3_CPLD_EN
J 0
(-3085 4135);
DISPLAY 0.617021 (-3085 4135);
PAINT ORANGE (-3085 4135);
WIRE 16 -1 (-3875 4275)(-2500 4275);
WIRE 16 -1 (-2500 4325)(-3100 4325);
FORCEPROP 0 LAST SIG_NAME FM_ADR_SMI_GPIO_N
J 0
(-3085 4335);
DISPLAY 0.617021 (-3085 4335);
PAINT ORANGE (-3085 4335);
DOT 1 (-1375 3325);
FORCENOTE
BOM_COST CPLD
(-8075 250) 0;
DISPLAY LEFT (-8075 250);
DISPLAY 2.148936 (-8075 250);
PAINT PURPLE (-8075 250);
FORCENOTE
ROOM CPLD
(-8075 400) 0;
DISPLAY LEFT (-8075 400);
DISPLAY 2.148936 (-8075 400);
PAINT PURPLE (-8075 400);
QUIT
